P  JOB   t6mg_pdb_a_v02_0109_1330.brd
P  UNITS CUST 
P  DIM   N
C  
C  Jan 13 14:12:20 2014
C  
C  IPC-D-356 Netlist From Allegro
C  
317N/C              J19   -H2   D1320UA00X+002998Y+003050               S0      
317GND              VIA   -     D0100PA00X+002522Y+001875               S3      
317GND              VIA   -     D0100PA00X+000300Y+005203               S3      
317N/C              J19   -H1   D1320UA00X+002998Y+007550               S0      
317GND              VIA   -     D0100PA00X+000300Y+010003               S3      
317GND              J33   -2    D0430PA00X+002276Y+011382               S0      
317CM_PWR_CTL_IN    J33   -1    D0430PA00X+002276Y+012563               S0      
317GND              VIA   -     D0100PA00X+000300Y+015003               S3      
317N/C              J21   -H2   D1320UA00X+002998Y+016650               S0      
317GND              VIA   -     D0100PA00X+000300Y+020003               S3      
317N/C              J21   -H1   D1320UA00X+002998Y+021150               S0      
317N/C              J23   -H2   D1320UA00X+002998Y+023950               S0      
317GND              VIA   -     D0100PA00X+000300Y+025003               S3      
317N/C              J23   -H1   D1320UA00X+002998Y+028450               S0      
317GND              J34   -3    D0430PA00X+002248Y+031684               S0      
317GND              VIA   -     D0100PA00X+000300Y+030003               S3      
317P12V             J34   -2    D0430PA00X+002248Y+032865               S0      
317GND              J34   -1    D0430PA00X+002248Y+034046               S0      
317N/C              J27   -H2   D1320UA00X+002998Y+037550               S0      
317GND              VIA   -     D0100PA00X+000300Y+035003               S3      
317N/C              J27   -H1   D1320UA00X+002998Y+042050               S0      
317GND              VIA   -     D0100PA00X+000300Y+040003               S3      
317GND              VIA   -     D0100PA00X+000300Y+045003               S3      
327N42130542        R150  -2          A01X+001344Y+050192X0180Y0200R270 S2      
327GND              R150  -1          A01X+001344Y+049877X0180Y0200R270 S2      
317N42130542        J29   -12   D0360PA00X+001407Y+051220               S0      
317N/C              J29   -H2   D1260UA00X+003025Y+051450               S0      
317GND              VIA   -     D0100PA00X+000300Y+050003               S3      
317GND              VIA   -     D0100PA00X+001344Y+049596               S3      
317N/C              J29   -11   D0360PA00X+001407Y+052200               S0      
317N42126673        J29   -10   D0360PA00X+001407Y+055200               S0      
317N42126764        J29   -9    D0360PA00X+001407Y+056180               S0      
317N/C              J29   -H1   D1260UA00X+003025Y+055950               S0      
317GND              VIA   -     D0100PA00X+000300Y+055003               S3      
327GND              R148  -2          A01X+001091Y+057621X0180Y0200R270 S2      
327N42126673        R148  -1          A01X+001091Y+057306X0180Y0200R270 S2      
327GND              R149  -2          A01X+001598Y+057628X0180Y0200R270 S2      
327N42126764        R149  -1          A01X+001598Y+057313X0180Y0200R270 S2      
317GND              VIA   -     D0100PA00X+001091Y+057885               S3      
317GND              VIA   -     D0100PA00X+001598Y+057885               S3      
317GND              VIA   -     D0100PA00X+000300Y+060003               S3      
317GND              VIA   -     D0100PA00X+000300Y+065003               S3      
317MATE_A1          J26   -B81  D0280PA00X+001555Y+070736               S0      
317P12V             J26   -A81  D0280PA00X+002539Y+070736               S0      
317P12V             J26   -B82  D0280PA00X+000767Y+070343               S0      
317N/C              J26   -H2   D0950UA00X+002047Y+069634               S0      
317GND              VIA   -     D0100PA00X+000300Y+070003               S3      
317P12V             J26   -B79  D0280PA00X+001555Y+071524               S0      
317GND              J26   -B77  D0280PA00X+001555Y+072311               S0      
317LAN1_P4_P        J26   -B75  D0280PA00X+001555Y+073099               S0      
317P12V             J26   -A79  D0280PA00X+002539Y+071524               S0      
317GND              J26   -A77  D0280PA00X+002539Y+072311               S0      
317LAN1_P2_P        J26   -A75  D0280PA00X+002539Y+073099               S0      
317P12V             J26   -B80  D0280PA00X+000767Y+071130               S0      
317CM_PWR_CTL_IN    J26   -B78  D0280PA00X+000767Y+071918               S0      
317LAN1_P4_N        J26   -B76  D0280PA00X+000767Y+072705               S0      
317LAN1_P3_N        J26   -B73  D0280PA00X+001555Y+073886               S0      
317GND              J26   -B71  D0280PA00X+001555Y+074673               S0      
317GND29            J26   -B69  D0280PA00X+001555Y+075461               S0      
317LAN1_P1_N        J26   -A73  D0280PA00X+002539Y+073886               S0      
317GND              J26   -A71  D0280PA00X+002539Y+074673               S0      
317N/C              J26   -A69  D0280PA00X+002539Y+075461               S0      
317GND              J26   -B74  D0280PA00X+000767Y+073492               S0      
317LAN1_P3_P        J26   -B72  D0280PA00X+000767Y+074280               S0      
317N/C              J26   -B70  D0280PA00X+000767Y+075067               S0      
317GND28            J26   -B68  D0280PA00X+000767Y+075855               S0      
317GND              VIA   -     D0100PA00X+000300Y+075003               S3      
317N/C              J26   -B67  D0280PA00X+001555Y+076248               S0      
317NNAME10000       J26   -B65  D0280PA00X+001555Y+077036               S0      
317UART_TX_P1_L     J26   -B63  D0280PA00X+001555Y+077823               S0      
317N/C              J26   -A67  D0280PA00X+002539Y+076248               S0      
317NNAME10001       J26   -A65  D0280PA00X+002539Y+077036               S0      
317UART_TX_P2_L     J26   -A63  D0280PA00X+002539Y+077823               S0      
317GND              J26   -B66  D0280PA00X+000767Y+076642               S0      
317NNAME10002       J26   -B64  D0280PA00X+000767Y+077429               S0      
317UART_RX_P1_L     J26   -B62  D0280PA00X+000767Y+078217               S0      
317NNAME10003       J26   -B61  D0280PA00X+001555Y+078611               S0      
317GND              J26   -B59  D0280PA00X+001555Y+079398               S0      
317NNAME10004       J26   -B57  D0280PA00X+001555Y+080185               S0      
317NNAME10005       J26   -A61  D0280PA00X+002539Y+078611               S0      
317GND              J26   -A59  D0280PA00X+002539Y+079398               S0      
317NNAME10006       J26   -A57  D0280PA00X+002539Y+080185               S0      
317NNAME10007       J26   -B60  D0280PA00X+000767Y+079004               S0      
317UART_RI_P5_L_N   J26   -B58  D0280PA00X+000767Y+079792               S0      
317NNAME10008       J26   -B56  D0280PA00X+000767Y+080579               S0      
317GND              VIA   -     D0100PA00X+000300Y+080003               S3      
317UART_TX_P5_L     J26   -B55  D0280PA00X+001555Y+080973               S0      
317NNAME10009       J26   -B53  D0280PA00X+001555Y+081760               S0      
317GND              J26   -B51  D0280PA00X+001555Y+082548               S0      
317UART_TX_P6_L     J26   -A55  D0280PA00X+002539Y+080973               S0      
317NNAME10010       J26   -A53  D0280PA00X+002539Y+081760               S0      
317GND              J26   -A51  D0280PA00X+002539Y+082548               S0      
317UART_RX_P5_L     J26   -B54  D0280PA00X+000767Y+081366               S0      
317NNAME10011       J26   -B52  D0280PA00X+000767Y+082154               S0      
317PSU6_AC_OK       J26   -B50  D0280PA00X+000767Y+082941               S0      
317PSU5_AC_OK       J26   -B49  D0280PA00X+001555Y+083335               S0      
317PSU3_AC_OK       J26   -B47  D0280PA00X+001555Y+084122               S0      
317PSU1_AC_OK       J26   -B45  D0280PA00X+001555Y+084910               S0      
317PSU5_DC_OK       J26   -A49  D0280PA00X+002539Y+083335               S0      
317PSU3_DC_OK       J26   -A47  D0280PA00X+002539Y+084122               S0      
317PSU1_DC_OK       J26   -A45  D0280PA00X+002539Y+084910               S0      
317PSU4_AC_OK       J26   -B48  D0280PA00X+000767Y+083729               S0      
317PSU2_AC_OK       J26   -B46  D0280PA00X+000767Y+084516               S0      
317GND              J26   -B44  D0280PA00X+000767Y+085303               S0      
317GND              VIA   -     D0100PA00X+000300Y+085003               S3      
317I2C_PSU1_SDA     J26   -B43  D0280PA00X+001555Y+085697               S0      
317GND              J26   -B41  D0280PA00X+001555Y+086485               S0      
317T2_BLAD4_RXD     J26   -B39  D0280PA00X+001555Y+087272               S0      
317T1_BLAD1_TXD     J26   -A43  D0280PA00X+002539Y+085697               S0      
317T1_BLAD4_TXD     J26   -A41  D0280PA00X+002539Y+086485               S0      
317GND              J26   -A39  D0280PA00X+002539Y+087272               S0      
317I2C_PSU1_SCL     J26   -B42  D0280PA00X+000767Y+086091               S0      
317T2_BLAD4_TXD     J26   -B40  D0280PA00X+000767Y+086878               S0      
317T2_BLAD3_TXD     J26   -B38  D0280PA00X+000767Y+087666               S0      
317T2_BLAD3_RXD     J26   -B37  D0280PA00X+001555Y+088059               S0      
317T2_BLAD2_TXD     J26   -B35  D0280PA00X+001555Y+088847               S0      
317T2_BLAD1_TXD     J26   -B33  D0280PA00X+001555Y+089634               S0      
317T1_BLAD3_RXD     J26   -A37  D0280PA00X+002539Y+088059               S0      
317T1_BLAD2_RXD     J26   -A35  D0280PA00X+002539Y+088847               S0      
317TP_T1_BLAD4_EN   J26   -A33  D0280PA00X+002539Y+089634               S0      
317GND              J26   -B36  D0280PA00X+000767Y+088453               S0      
317T2_BLAD2_RXD     J26   -B34  D0280PA00X+000767Y+089240               S0      
317T2_BLAD1_RXD     J26   -B32  D0280PA00X+000767Y+090028               S0      
317GND              VIA   -     D0100PA00X+000300Y+090003               S3      
317GND              J26   -B31  D0280PA00X+001555Y+090422               S0      
317T2_BLAD3_EN      J26   -B29  D0280PA00X+001555Y+091209               S0      
317T2_BLAD1_EN      J26   -B27  D0280PA00X+001555Y+091996               S0      
317T1_BLAD2_EN      J26   -A31  D0280PA00X+002539Y+090422               S0      
317GND              J26   -A29  D0280PA00X+002539Y+091209               S0      
317T3_BLAD4_RXD     J26   -A27  D0280PA00X+002539Y+091996               S0      
317TP_T2_BLAD4_EN   J26   -B30  D0280PA00X+000767Y+090815               S0      
317TP_T2_BLAD2_EN   J26   -B28  D0280PA00X+000767Y+091603               S0      
317GND              J26   -B26  D0280PA00X+000767Y+092390               S0      
317T4_BLAD4_TXD     J26   -B25  D0280PA00X+001555Y+092784               S0      
317T4_BLAD3_TXD     J26   -B23  D0280PA00X+001555Y+093571               S0      
317GND              J26   -B21  D0280PA00X+001555Y+094359               S0      
317T4_BLAD2_RXD     J26   -B19  D0280PA00X+001555Y+095146               S0      
317T3_BLAD3_RXD     J26   -A25  D0280PA00X+002539Y+092784               S0      
317T3_BLAD2_TXD     J26   -A23  D0280PA00X+002539Y+093571               S0      
317T3_BLAD1_TXD     J26   -A21  D0280PA00X+002539Y+094359               S0      
317GND              J26   -A19  D0280PA00X+002539Y+095146               S0      
317T4_BLAD4_RXD     J26   -B24  D0280PA00X+000767Y+093177               S0      
317T4_BLAD3_RXD     J26   -B22  D0280PA00X+000767Y+093965               S0      
317T4_BLAD2_TXD     J26   -B20  D0280PA00X+000767Y+094752               S0      
317GND              VIA   -     D0100PA00X+000300Y+095003               S3      
317T4_BLAD1_RXD     J26   -B17  D0280PA00X+001555Y+095933               S0      
317TP_T4_BLAD4_EN   J26   -B15  D0280PA00X+001555Y+096721               S0      
317TP_T4_BLAD2_EN   J26   -B13  D0280PA00X+001555Y+097508               S0      
317T3_BLAD3_EN      J26   -A17  D0280PA00X+002539Y+095933               S0      
317T3_BLAD1_EN      J26   -A15  D0280PA00X+002539Y+096721               S0      
317T5_BLAD4_TXD     J26   -A13  D0280PA00X+002539Y+097508               S0      
317T4_BLAD1_TXD     J26   -B18  D0280PA00X+000767Y+095540               S0      
317GND              J26   -B16  D0280PA00X+000767Y+096327               S0      
317T4_BLAD3_EN      J26   -B14  D0280PA00X+000767Y+097114               S0      
317T4_BLAD1_EN      J26   -B12  D0280PA00X+000767Y+097902               S0      
317I2C_PSU2_SCL     J26   -B10  D0280PA00X+000767Y+099477               S0      
317I2C_PSU2_SDA     J26   -B11  D0280PA00X+001555Y+099083               S0      
317GND              J26   -B9   D0280PA00X+001555Y+099870               S0      
317T5_BLAD3_TXD     J26   -A11  D0280PA00X+002539Y+099083               S0      
317T5_BLAD2_TXD     J26   -A9   D0280PA00X+002539Y+099870               S0      
317N/C              J26   -H1   D0950UA00X+002047Y+098433               S0      
317T6_BLAD4_TXD     J26   -B8   D0280PA00X+000767Y+100264               S0      
317T6_BLAD3_TXD     J26   -B6   D0280PA00X+000767Y+101051               S0      
317GND              J26   -B4   D0280PA00X+000767Y+101839               S0      
317T6_BLAD4_RXD     J26   -B7   D0280PA00X+001555Y+100658               S0      
317T6_BLAD3_RXD     J26   -B5   D0280PA00X+001555Y+101445               S0      
317T6_BLAD2_TXD     J26   -B3   D0280PA00X+001555Y+102233               S0      
317GND              J26   -A7   D0280PA00X+002539Y+100658               S0      
317T5_BLAD1_RXD     J26   -A5   D0280PA00X+002539Y+101445               S0      
317TP_T5_BLAD4_EN   J26   -A3   D0280PA00X+002539Y+102233               S0      
317GND              VIA   -     D0100PA00X+000300Y+100003               S3      
317T6_BLAD2_RXD     J26   -B2   D0280PA00X+000767Y+102626               S0      
317GND              J26   -B1   D0280PA00X+001555Y+103020               S0      
317GND              J26   -A1   D0280PA00X+002539Y+103020               S0      
317T6_BLAD1_RXD     J25   -B81  D0280PA00X+001555Y+106563               S0      
317T5_BLAD1_EN      J25   -A81  D0280PA00X+002539Y+106563               S0      
317T6_BLAD1_TXD     J25   -B82  D0280PA00X+000768Y+106169               S0      
317GND              J25   -B80  D0280PA00X+000768Y+106957               S0      
317N/C              J25   -H2   D0950UA00X+002047Y+105461               S0      
317GND              VIA   -     D0100PA00X+000300Y+105003               S3      
317TP_T6_BLAD4_EN   J25   -B79  D0280PA00X+001555Y+107350               S0      
317TP_T6_BLAD2_EN   J25   -B77  D0280PA00X+001555Y+108138               S0      
317GND              J25   -B75  D0280PA00X+001555Y+108925               S0      
317GND              J25   -A79  D0280PA00X+002539Y+107350               S0      
317T7_BLAD4_RXD     J25   -A77  D0280PA00X+002539Y+108138               S0      
317T7_BLAD3_RXD     J25   -A75  D0280PA00X+002539Y+108925               S0      
317T6_BLAD3_EN      J25   -B78  D0280PA00X+000768Y+107744               S0      
317T6_BLAD1_EN      J25   -B76  D0280PA00X+000768Y+108531               S0      
317T8_BLAD4_TXD     J25   -B74  D0280PA00X+000768Y+109319               S0      
317T8_BLAD4_RXD     J25   -B73  D0280PA00X+001555Y+109713               S0      
317T8_BLAD3_RXD     J25   -B71  D0280PA00X+001555Y+110500               S0      
317T8_BLAD2_TXD     J25   -B69  D0280PA00X+001555Y+111287               S0      
317T8_BLAD1_TXD     J25   -B67  D0280PA00X+001555Y+112075               S0      
317T7_BLAD2_TXD     J25   -A73  D0280PA00X+002539Y+109713               S0      
317T7_BLAD1_TXD     J25   -A71  D0280PA00X+002539Y+110500               S0      
317GND              J25   -A69  D0280PA00X+002539Y+111287               S0      
317T7_BLAD3_EN      J25   -A67  D0280PA00X+002539Y+112075               S0      
317T8_BLAD3_TXD     J25   -B72  D0280PA00X+000768Y+110106               S0      
317GND              J25   -B70  D0280PA00X+000768Y+110894               S0      
317T8_BLAD2_RXD     J25   -B68  D0280PA00X+000768Y+111681               S0      
317GND              VIA   -     D0100PA00X+000300Y+110003               S3      
317GND              J25   -B65  D0280PA00X+001555Y+112862               S0      
317T8_BLAD3_EN      J25   -B63  D0280PA00X+001555Y+113650               S0      
317T8_BLAD1_EN      J25   -B61  D0280PA00X+001555Y+114437               S0      
317T7_BLAD1_EN      J25   -A65  D0280PA00X+002539Y+112862               S0      
317T9_BLAD4_TXD     J25   -A63  D0280PA00X+002539Y+113650               S0      
317T9_BLAD3_TXD     J25   -A61  D0280PA00X+002539Y+114437               S0      
317T8_BLAD1_RXD     J25   -B66  D0280PA00X+000768Y+112468               S0      
317TP_T8_BLAD4_EN   J25   -B64  D0280PA00X+000768Y+113256               S0      
317TP_T8_BLAD2_EN   J25   -B62  D0280PA00X+000768Y+114043               S0      
317T10_BLAD4_TXD    J25   -B59  D0280PA00X+001555Y+115224               S0      
317T10_BLAD3_TXD    J25   -B57  D0280PA00X+001555Y+116012               S0      
317GND              J25   -B55  D0280PA00X+001555Y+116799               S0      
317GND              J25   -A59  D0280PA00X+002539Y+115224               S0      
317T9_BLAD2_RXD     J25   -A57  D0280PA00X+002539Y+116012               S0      
317T9_BLAD1_RXD     J25   -A55  D0280PA00X+002539Y+116799               S0      
317GND              J25   -B60  D0280PA00X+000768Y+114831               S0      
317T10_BLAD4_RXD    J25   -B58  D0280PA00X+000768Y+115618               S0      
317T10_BLAD3_RXD    J25   -B56  D0280PA00X+000768Y+116406               S0      
317GND              VIA   -     D0100PA00X+000300Y+115003               S3      
317T10_BLAD2_RXD    J25   -B53  D0280PA00X+001555Y+117587               S0      
317T10_BLAD1_RXD    J25   -B51  D0280PA00X+001555Y+118374               S0      
317NNAME10012       J25   -B49  D0280PA00X+001555Y+119161               S0      
317TP_T9_BLAD4_EN   J25   -A53  D0280PA00X+002539Y+117587               S0      
317TP_T9_BLAD2_EN   J25   -A51  D0280PA00X+002539Y+118374               S0      
317GND              J25   -A49  D0280PA00X+002539Y+119161               S0      
317T10_BLAD2_TXD    J25   -B54  D0280PA00X+000768Y+117193               S0      
317T10_BLAD1_TXD    J25   -B52  D0280PA00X+000768Y+117980               S0      
317GND              J25   -B50  D0280PA00X+000768Y+118768               S0      
317NNAME10013       J25   -B47  D0280PA00X+001555Y+119949               S0      
317GND              J25   -B45  D0280PA00X+001555Y+120736               S0      
317T12_BLAD4_RXD    J25   -B43  D0280PA00X+001555Y+121524               S0      
317T11_BLAD4_RXD    J25   -A47  D0280PA00X+002539Y+119949               S0      
317T11_BLAD3_RXD    J25   -A45  D0280PA00X+002539Y+120736               S0      
317T11_BLAD2_TXD    J25   -A43  D0280PA00X+002539Y+121524               S0      
317T10_BLAD3_EN     J25   -B48  D0280PA00X+000768Y+119555               S0      
317T10_BLAD1_EN     J25   -B46  D0280PA00X+000768Y+120343               S0      
317T12_BLAD4_TXD    J25   -B44  D0280PA00X+000768Y+121130               S0      
317GND              VIA   -     D0100PA00X+000300Y+120003               S3      
317T12_BLAD3_RXD    J25   -B41  D0280PA00X+001555Y+122311               S0      
317T12_BLAD2_TXD    J25   -B39  D0280PA00X+001555Y+123098               S0      
317T12_BLAD1_TXD    J25   -B37  D0280PA00X+001555Y+123886               S0      
317T11_BLAD1_TXD    J25   -A41  D0280PA00X+002539Y+122311               S0      
317GND              J25   -A39  D0280PA00X+002539Y+123098               S0      
317T11_BLAD3_EN     J25   -A37  D0280PA00X+002539Y+123886               S0      
317T12_BLAD3_TXD    J25   -B42  D0280PA00X+000768Y+121917               S0      
317GND              J25   -B40  D0280PA00X+000768Y+122705               S0      
317T12_BLAD2_RXD    J25   -B38  D0280PA00X+000768Y+123492               S0      
317GND              J25   -B35  D0280PA00X+001555Y+124673               S0      
317T12_BLAD3_EN     J25   -B33  D0280PA00X+001555Y+125461               S0      
317T12_BLAD1_EN     J25   -B31  D0280PA00X+001555Y+126248               S0      
317T11_BLAD1_EN     J25   -A35  D0280PA00X+002539Y+124673               S0      
317I2C_PSU3_SDA     J25   -A33  D0280PA00X+002539Y+125461               S0      
317GND              J25   -A31  D0280PA00X+002539Y+126248               S0      
317T12_BLAD1_RXD    J25   -B36  D0280PA00X+000768Y+124280               S0      
317NNAME10014       J25   -B34  D0280PA00X+000768Y+125067               S0      
317NNAME10015       J25   -B32  D0280PA00X+000768Y+125854               S0      
317GND              VIA   -     D0100PA00X+000300Y+125003               S3      
317FAN3_TACH        J25   -B29  D0280PA00X+001555Y+127035               S0      
317FAN1_TACH        J25   -B27  D0280PA00X+001555Y+127823               S0      
317GND8             J25   -B25  D0280PA00X+001555Y+128610               S0      
317GND              J25   -A29  D0280PA00X+002539Y+127035               S0      
317FAN5_TACH        J25   -A27  D0280PA00X+002539Y+127823               S0      
317GND              J25   -A25  D0280PA00X+002539Y+128610               S0      
317GND              J25   -B30  D0280PA00X+000768Y+126642               S0      
317FAN2_TACH        J25   -B28  D0280PA00X+000768Y+127429               S0      
317GND              J25   -B26  D0280PA00X+000768Y+128217               S0      
317N/C              J25   -B23  D0280PA00X+001555Y+129398               S0      
317GND6             J25   -B21  D0280PA00X+001555Y+130185               S0      
317N/C              J25   -B19  D0280PA00X+001555Y+130972               S0      
317GND40            J25   -A23  D0280PA00X+002539Y+129398               S0      
317N/C              J25   -A21  D0280PA00X+002539Y+130185               S0      
317N/C              J25   -A19  D0280PA00X+002539Y+130972               S0      
317N/C              J25   -B24  D0280PA00X+000768Y+129004               S0      
317GND7             J25   -B22  D0280PA00X+000768Y+129791               S0      
317N/C              J25   -B20  D0280PA00X+000768Y+130579               S0      
317GND              J25   -B18  D0280PA00X+000768Y+131366               S0      
317GND              VIA   -     D0100PA00X+000300Y+130003               S3      
317N/C              J25   -B17  D0280PA00X+001555Y+131760               S0      
317N/C              J25   -B15  D0280PA00X+001555Y+132547               S0      
317GND3             J25   -B13  D0280PA00X+001555Y+133335               S0      
317GND              J25   -A17  D0280PA00X+002539Y+131760               S0      
317GND37            J25   -A15  D0280PA00X+002539Y+132547               S0      
317N/C              J25   -A13  D0280PA00X+002539Y+133335               S0      
317GND4             J25   -B16  D0280PA00X+000768Y+132154               S0      
317N/C              J25   -B14  D0280PA00X+000768Y+132941               S0      
317P3V3             J25   -B12  D0280PA00X+000768Y+133728               S0      
317I2C_PDB_SCL      J25   -B10  D0280PA00X+000768Y+135303               S0      
317GND              J25   -B8   D0280PA00X+000768Y+136091               S0      
317I2C_PDB_SDA      J25   -B11  D0280PA00X+001555Y+134909               S0      
317GND              J25   -B9   D0280PA00X+001555Y+135697               S0      
317NNAME10016       J25   -A11  D0280PA00X+002539Y+134909               S0      
317NNAME10017       J25   -A9   D0280PA00X+002539Y+135697               S0      
317N/C              J25   -H1   D0950UA00X+002047Y+134260               S0      
317GND              VIA   -     D0100PA00X+000300Y+135003               S3      
317LAN2_P2_N        J25   -B6   D0280PA00X+000768Y+136878               S0      
317GND              J25   -B4   D0280PA00X+000768Y+137665               S0      
317LAN2_P1_P        J25   -B2   D0280PA00X+000768Y+138453               S0      
317GND              J25   -B7   D0280PA00X+001555Y+136484               S0      
317LAN2_P2_P        J25   -B5   D0280PA00X+001555Y+137272               S0      
317LAN2_P1_N        J25   -B3   D0280PA00X+001555Y+138059               S0      
317LAN2_P4_N        J25   -A7   D0280PA00X+002539Y+136484               S0      
317GND              J25   -A5   D0280PA00X+002539Y+137272               S0      
317LAN2_P3_P        J25   -A3   D0280PA00X+002539Y+138059               S0      
317GND              J25   -B1   D0280PA00X+001555Y+138846               S0      
317MATE_A1          J25   -A1   D0280PA00X+002539Y+138846               S0      
317GND              VIA   -     D0100PA00X+000300Y+140003               S3      
317GND              VIA   -     D0100PA00X+000300Y+145003               S3      
317GND              VIA   -     D0100PA00X+000300Y+150003               S3      
317GND              VIA   -     D0100PA00X+000300Y+155003               S3      
327N42132358        R153  -2          A01X+001469Y+155928X0180Y0200R180 S2      
327GND              R153  -1          A01X+001154Y+155928X0180Y0200R180 S2      
317N/C              J28   -11   D0360PA00X+001407Y+158000               S0      
317N42132358        J28   -12   D0360PA00X+001407Y+157020               S0      
317N/C              J28   -H2   D1260UA00X+003025Y+157250               S0      
317GND              VIA   -     D0100PA00X+001154Y+156233               S3      
317GND              VIA   -     D0100PA00X+000301Y+159460               S3      
317N42132545        J28   -10   D0360PA00X+001407Y+161000               S0      
317N42132933        J28   -9    D0360PA00X+001407Y+161981               S0      
317N/C              J28   -H1   D1260UA00X+003025Y+161750               S0      
317GND              VIA   -     D0100PA00X+000301Y+161017               S3      
327GND              R151  -2          A01X+001115Y+163544X0180Y0200R270 S2      
327N42132545        R151  -1          A01X+001115Y+163229X0180Y0200R270 S2      
327GND              R152  -2          A01X+001655Y+163530X0180Y0200R270 S2      
327N42132933        R152  -1          A01X+001655Y+163215X0180Y0200R270 S2      
317GND              VIA   -     D0100PA00X+000300Y+165003               S3      
317GND              VIA   -     D0100PA00X+001115Y+163844               S3      
317GND              VIA   -     D0100PA00X+001655Y+163801               S3      
317FAN_PWM          J20   -20   D0570PA00X+002340Y+166887               S0      
317GND              J20   -19   D0570PA00X+002340Y+168541               S0      
317GND              J20   -18   D0570PA00X+002340Y+170195               S0      
317FAN_PWM          J20   -17   D0570PA00X+002340Y+171848               S0      
317GND              VIA   -     D0100PA00X+000300Y+170003               S3      
317GND              J20   -16   D0570PA00X+002340Y+173502               S0      
317GND              J20   -15   D0570PA00X+002340Y+175155               S0      
317FAN6_TACH        J20   -14   D0570PA00X+002340Y+176809               S0      
317GND              VIA   -     D0100PA00X+000300Y+175003               S3      
317GND              J20   -13   D0570PA00X+002340Y+178462               S0      
317FAN5_TACH        J20   -11   D0570PA00X+002340Y+181769               S0      
317GND              J20   -12   D0570PA00X+002340Y+180116               S0      
317GND              VIA   -     D0100PA00X+000300Y+180003               S3      
317GND              J30   -2    D0430PA00X+002276Y+186682               S0      
317GND              VIA   -     D0100PA00X+000300Y+185003               S3      
317NNAME10017       J30   -1    D0430PA00X+002276Y+187863               S0      
317GND              VIA   -     D0100PA00X+000300Y+190003               S3      
317GND              J31   -2    D0430PA00X+002276Y+194882               S0      
317NNAME10018       J31   -1    D0430PA00X+002276Y+196063               S0      
317GND              VIA   -     D0100PA00X+000300Y+195003               S3      
317GND              VIA   -     D0100PA00X+000300Y+200003               S3      
317GND              J32   -2    D0430PA00X+002276Y+202382               S0      
317NNAME10016       J32   -1    D0430PA00X+002276Y+203563               S0      
317GND              VIA   -     D0100PA00X+000300Y+205003               S3      
317N/C              J33   -H2   D0520UA00X+003047Y+010201               S0      
317N/C              J33   -H1   D0520UA00X+003047Y+013744               S0      
317N/C              J34   -H2   D0520UA00X+003020Y+030503               S0      
317N/C              J34   -H1   D0520UA00X+003020Y+035227               S0      
317GND              J29   -G2   D0630PA00X+004541Y+050600               S0      
317GND              J29   -G1   D0630PA00X+004541Y+056800               S0      
317P12V             J26   -A82  D0280PA00X+003326Y+070343               S0      
317P12V             J26   -A80  D0280PA00X+003326Y+071130               S0      
317P12V             J26   -A78  D0280PA00X+003326Y+071918               S0      
317LAN1_P2_N        J26   -A76  D0280PA00X+003326Y+072705               S0      
317GND              J26   -A74  D0280PA00X+003326Y+073492               S0      
317LAN1_P1_P        J26   -A72  D0280PA00X+003326Y+074280               S0      
317GND61            J26   -A70  D0280PA00X+003326Y+075067               S0      
317N/C              J26   -A68  D0280PA00X+003326Y+075855               S0      
317GND              J26   -A66  D0280PA00X+003326Y+076642               S0      
317NNAME10019       J26   -A64  D0280PA00X+003326Y+077429               S0      
317UART_RX_P2_L     J26   -A62  D0280PA00X+003326Y+078217               S0      
317NNAME10020       J26   -A60  D0280PA00X+003326Y+079004               S0      
317UART_RI_P6_L_N   J26   -A58  D0280PA00X+003326Y+079792               S0      
317NNAME10021       J26   -A56  D0280PA00X+003326Y+080579               S0      
317UART_RX_P6_L     J26   -A54  D0280PA00X+003326Y+081366               S0      
317NNAME10022       J26   -A52  D0280PA00X+003326Y+082154               S0      
317PSU6_DC_OK       J26   -A50  D0280PA00X+003326Y+082941               S0      
317PSU4_DC_OK       J26   -A48  D0280PA00X+003326Y+083729               S0      
317PSU2_DC_OK       J26   -A46  D0280PA00X+003326Y+084516               S0      
317GND              J26   -A44  D0280PA00X+003326Y+085303               S0      
317T1_BLAD1_RXD     J26   -A42  D0280PA00X+003326Y+086091               S0      
317T1_BLAD4_RXD     J26   -A40  D0280PA00X+003326Y+086878               S0      
317T1_BLAD3_TXD     J26   -A38  D0280PA00X+003326Y+087666               S0      
317T1_BLAD1_TXD     VIA   -     D0100PA00X+004843Y+086618               S3      
317T1_BLAD1_RXD     VIA   -     D0100PA00X+004847Y+086928               S3      
317T1_BLAD2_TXD     J26   -A36  D0280PA00X+003326Y+088453               S0      
317GND              J26   -A34  D0280PA00X+003326Y+089240               S0      
317T1_BLAD3_EN      J26   -A32  D0280PA00X+003326Y+090028               S0      
327TP_T1_BLAD4_EN   VIA   -           A01X+004579Y+089634X0300Y0300     S2      
317T1_BLAD1_EN      J26   -A30  D0280PA00X+003326Y+090815               S0      
317T3_BLAD4_TXD     J26   -A28  D0280PA00X+003326Y+091603               S0      
317T3_BLAD3_TXD     J26   -A26  D0280PA00X+003326Y+092390               S0      
327T1_BLAD2_EN      VIA   -           A01X+004602Y+090422X0300Y0300     S2      
327TP_T2_BLAD2_EN   VIA   -           A01X+004809Y+091999X0300Y0300     S2      
327TP_T2_BLAD4_EN   VIA   -           A01X+004598Y+091191X0300Y0300     S2      
317GND              J26   -A24  D0280PA00X+003326Y+093177               S0      
317T3_BLAD2_RXD     J26   -A22  D0280PA00X+003326Y+093965               S0      
317T3_BLAD1_RXD     J26   -A20  D0280PA00X+003326Y+094752               S0      
317TP_T3_BLAD4_EN   J26   -A18  D0280PA00X+003326Y+095540               S0      
317TP_T3_BLAD2_EN   J26   -A16  D0280PA00X+003326Y+096327               S0      
317GND              J26   -A14  D0280PA00X+003326Y+097114               S0      
327TP_T3_BLAD2_EN   VIA   -           A01X+004784Y+096010X0300Y0300     S2      
317T5_BLAD4_RXD     J26   -A12  D0280PA00X+003326Y+097902               S0      
317T5_BLAD3_RXD     J26   -A10  D0280PA00X+003326Y+099477               S0      
327TP_T4_BLAD2_EN   VIA   -           A01X+004711Y+097560X0300Y0300     S2      
317T5_BLAD2_RXD     J26   -A8   D0280PA00X+003326Y+100264               S0      
317T5_BLAD1_TXD     J26   -A6   D0280PA00X+003326Y+101051               S0      
317GND              J26   -A4   D0280PA00X+003326Y+101839               S0      
327TP_T5_BLAD4_EN   VIA   -           A01X+004820Y+102233X0300Y0300     S2      
317T5_BLAD3_EN      J26   -A2   D0280PA00X+003326Y+102626               S0      
317TP_T5_BLAD2_EN   J25   -A82  D0280PA00X+003327Y+106169               S0      
317PSU_ALERT_N      J25   -A80  D0280PA00X+003327Y+106957               S0      
327TP_T5_BLAD2_EN   VIA   -           A01X+004747Y+106169X0300Y0300     S2      
317T7_BLAD4_TXD     J25   -A78  D0280PA00X+003327Y+107744               S0      
317T7_BLAD3_TXD     J25   -A76  D0280PA00X+003327Y+108531               S0      
317GND              J25   -A74  D0280PA00X+003327Y+109319               S0      
327TP_T6_BLAD2_EN   VIA   -           A01X+004783Y+108563X0300Y0300     S2      
327TP_T6_BLAD4_EN   VIA   -           A01X+004767Y+107569X0300Y0300     S2      
317T7_BLAD2_RXD     J25   -A72  D0280PA00X+003327Y+110106               S0      
317T7_BLAD1_RXD     J25   -A70  D0280PA00X+003327Y+110894               S0      
317TP_T7_BLAD4_EN   J25   -A68  D0280PA00X+003327Y+111681               S0      
327TP_T7_BLAD4_EN   VIA   -           A01X+004741Y+111459X0300Y0300     S2      
317TP_T7_BLAD2_EN   J25   -A66  D0280PA00X+003327Y+112468               S0      
317GND              J25   -A64  D0280PA00X+003327Y+113256               S0      
317T9_BLAD4_RXD     J25   -A62  D0280PA00X+003327Y+114043               S0      
327TP_T8_BLAD2_EN   VIA   -           A01X+004754Y+113677X0300Y0300     S2      
327TP_T8_BLAD4_EN   VIA   -           A01X+004699Y+112924X0300Y0300     S2      
327TP_T7_BLAD2_EN   VIA   -           A01X+004708Y+112166X0300Y0300     S2      
317T9_BLAD3_RXD     J25   -A60  D0280PA00X+003327Y+114831               S0      
317T9_BLAD2_TXD     J25   -A58  D0280PA00X+003327Y+115618               S0      
317T9_BLAD1_TXD     J25   -A56  D0280PA00X+003327Y+116406               S0      
317GND              J25   -A54  D0280PA00X+003327Y+117193               S0      
317T9_BLAD3_EN      J25   -A52  D0280PA00X+003327Y+117980               S0      
317T9_BLAD1_EN      J25   -A50  D0280PA00X+003327Y+118768               S0      
317T11_BLAD4_TXD    J25   -A48  D0280PA00X+003327Y+119555               S0      
317T11_BLAD3_TXD    J25   -A46  D0280PA00X+003327Y+120343               S0      
317GND              J25   -A44  D0280PA00X+003327Y+121130               S0      
327NNAME10013       VIA   -           A01X+004632Y+121587X0300Y0300     S2      
327NNAME10012       VIA   -           A01X+004986Y+120871X0300Y0300     S2      
327TP_T9_BLAD2_EN   VIA   -           A01X+004582Y+120235X0300Y0300     S2      
327TP_T9_BLAD4_EN   VIA   -           A01X+004657Y+119483X0300Y0300     S2      
317T11_BLAD2_RXD    J25   -A42  D0280PA00X+003327Y+121917               S0      
317T11_BLAD1_RXD    J25   -A40  D0280PA00X+003327Y+122705               S0      
317NNAME10023       J25   -A38  D0280PA00X+003327Y+123492               S0      
317T11_BLAD2_TXD    VIA   -     D0100PA00X+004944Y+123896               S1      
327NNAME10023       VIA   -           A01X+004640Y+123161X0300Y0300     S2      
317NNAME10024       J25   -A36  D0280PA00X+003327Y+124280               S0      
317GND              J25   -A34  D0280PA00X+003327Y+125067               S0      
317I2C_PSU3_SCL     J25   -A32  D0280PA00X+003327Y+125854               S0      
327NNAME10024       VIA   -           A01X+004572Y+124280X0300Y0300     S2      
317FAN_PWM          J25   -A30  D0280PA00X+003327Y+126642               S0      
317FAN6_TACH        J25   -A28  D0280PA00X+003327Y+127429               S0      
317FAN4_TACH        J25   -A26  D0280PA00X+003327Y+128217               S0      
317GND8             VIA   -     D0100PA00X+004558Y+127842               S1      
317GND41            VIA   -     D0100PA00X+004541Y+128372               S1      
317GND40            VIA   -     D0100PA00X+004524Y+128907               S1      
317GND41            J25   -A24  D0280PA00X+003327Y+129004               S0      
317N/C              J25   -A22  D0280PA00X+003327Y+129791               S0      
317GND39            J25   -A20  D0280PA00X+003327Y+130579               S0      
317GND38            J25   -A18  D0280PA00X+003327Y+131366               S0      
327P3V3             VIA   -           A01X+004994Y+131134X0300Y0300     S2      
317GND6             VIA   -     D0100PA00X+004535Y+129970               S1      
317GND7             VIA   -     D0100PA00X+004527Y+129420               S1      
317GND38            VIA   -     D0100PA00X+004528Y+131089               S1      
317GND39            VIA   -     D0100PA00X+004524Y+130579               S1      
317N/C              J25   -A16  D0280PA00X+003327Y+132154               S0      
317N/C              J25   -A14  D0280PA00X+003327Y+132941               S0      
317GND36            J25   -A12  D0280PA00X+003327Y+133728               S0      
317P3V3             VIA   -     D0100PA00X+004698Y+133584               S3      
317GND3             VIA   -     D0100PA00X+004698Y+132584               S1      
317GND4             VIA   -     D0100PA00X+004698Y+131584               S1      
317GND37            VIA   -     D0100PA00X+004698Y+132084               S1      
317GND36            VIA   -     D0100PA00X+004698Y+133084               S1      
317NNAME10018       J25   -A10  D0280PA00X+003327Y+135303               S0      
317GND              J25   -A8   D0280PA00X+003327Y+136091               S0      
317I2C_PDB_SCL      VIA   -     D0100PA00X+004698Y+134584               S1      
317I2C_PDB_SDA      VIA   -     D0100PA00X+004698Y+134084               S1      
317LAN2_P4_P        J25   -A6   D0280PA00X+003327Y+136878               S0      
317LAN2_P3_N        J25   -A4   D0280PA00X+003327Y+137665               S0      
317GND              J25   -A2   D0280PA00X+003327Y+138453               S0      
317GND              J28   -G2   D0630PA00X+004541Y+156400               S0      
317GND              J28   -G1   D0630PA00X+004541Y+162601               S0      
317FAN4_TACH        J20   -10   D0570PA00X+004506Y+166887               S0      
317P12V             J20   -9    D0570PA00X+004506Y+168541               S0      
317P12V             J20   -8    D0570PA00X+004506Y+170195               S0      
317FAN3_TACH        J20   -7    D0570PA00X+004506Y+171848               S0      
317P12V             J20   -6    D0570PA00X+004506Y+173502               S0      
317P12V             J20   -5    D0570PA00X+004506Y+175155               S0      
317FAN2_TACH        J20   -4    D0570PA00X+004506Y+176809               S0      
317P12V             J20   -3    D0570PA00X+004506Y+178462               S0      
317FAN1_TACH        J20   -1    D0570PA00X+004506Y+181769               S0      
317P12V             J20   -2    D0570PA00X+004506Y+180116               S0      
317N/C              J30   -H2   D0520UA00X+003047Y+185501               S0      
317N/C              J30   -H1   D0520UA00X+003047Y+189044               S0      
317N/C              J31   -H2   D0520UA00X+003047Y+193701               S0      
317N/C              J31   -H1   D0520UA00X+003047Y+197244               S0      
317N/C              J32   -H2   D0520UA00X+003047Y+201201               S0      
317N/C              J32   -H1   D0520UA00X+003047Y+204744               S0      
317GND              VIA   -     D0100PA00X+002683Y+206787               S3      
317NNAME10000       J19   -8    D0390PA00X+006498Y+003550               S0      
317UART_TX_P1_L     J19   -6    D0390PA00X+006498Y+004550               S0      
317GND              J19   -4    D0390PA00X+006498Y+005550               S0      
317NNAME10002       J19   -7    D0390PA00X+005498Y+004050               S0      
317GND              J19   -5    D0390PA00X+005498Y+005050               S0      
317NNAME10003       J19   -2    D0390PA00X+006498Y+006550               S0      
317UART_RX_P1_L     J19   -3    D0390PA00X+005498Y+006050               S0      
317NNAME10007       J19   -1    D0390PA00X+005498Y+007050               S0      
317GND              H11   -6    D0220PA00X+006535Y+010118               S0      
317GND              H11   -5    D0220PA00X+005551Y+010512               S0      
317GND              H11   -4    D0220PA00X+005157Y+011496               S0      
317GND              H11   -3    D0220PA00X+005551Y+012480               S0      
317GND              H11   -2    D0220PA00X+006535Y+012874               S0      
317N/C              H11   -1    D1580UA00X+006535Y+011496               S0      
317NNAME10001       J21   -8    D0390PA00X+006498Y+017150               S0      
317NNAME10019       J21   -7    D0390PA00X+005498Y+017650               S0      
317UART_TX_P2_L     J21   -6    D0390PA00X+006498Y+018150               S0      
317GND              J21   -4    D0390PA00X+006498Y+019150               S0      
317NNAME10005       J21   -2    D0390PA00X+006498Y+020150               S0      
317GND              J21   -5    D0390PA00X+005498Y+018650               S0      
317UART_RX_P2_L     J21   -3    D0390PA00X+005498Y+019650               S0      
317NNAME10020       J21   -1    D0390PA00X+005498Y+020650               S0      
317NNAME10004       J23   -8    D0390PA00X+006498Y+024450               S0      
317NNAME10008       J23   -7    D0390PA00X+005498Y+024950               S0      
317UART_TX_P5_L     J23   -6    D0390PA00X+006498Y+025450               S0      
317UART_RI_P5_L_N   J23   -4    D0390PA00X+006498Y+026450               S0      
317NNAME10009       J23   -2    D0390PA00X+006498Y+027450               S0      
317GND              J23   -5    D0390PA00X+005498Y+025950               S0      
317UART_RX_P5_L     J23   -3    D0390PA00X+005498Y+026950               S0      
317NNAME10011       J23   -1    D0390PA00X+005498Y+027950               S0      
317NNAME10006       J27   -8    D0390PA00X+006498Y+038050               S0      
317UART_TX_P6_L     J27   -6    D0390PA00X+006498Y+039050               S0      
317NNAME10021       J27   -7    D0390PA00X+005498Y+038550               S0      
317GND              J27   -5    D0390PA00X+005498Y+039550               S0      
317UART_RI_P6_L_N   J27   -4    D0390PA00X+006498Y+040050               S0      
317NNAME10010       J27   -2    D0390PA00X+006498Y+041050               S0      
317UART_RX_P6_L     J27   -3    D0390PA00X+005498Y+040550               S0      
317NNAME10022       J27   -1    D0390PA00X+005498Y+041550               S0      
317GND              H10   -6    D0220PA00X+006535Y+045118               S0      
317GND              H10   -5    D0220PA00X+005551Y+045512               S0      
317GND              H10   -4    D0220PA00X+005157Y+046496               S0      
317N/C              H10   -1    D1580UA00X+006535Y+046496               S0      
317GND              H10   -3    D0220PA00X+005551Y+047480               S0      
317GND              H10   -2    D0220PA00X+006535Y+047874               S0      
317LAN1_P4_N        J29   -8    D0360PA00X+006525Y+051950               S0      
317LAN1_P2_N        J29   -6    D0360PA00X+006525Y+052950               S0      
317LAN1_P3_P        J29   -4    D0360PA00X+006525Y+053950               S0      
317LAN1_P4_P        J29   -7    D0360PA00X+005525Y+052450               S0      
317LAN1_P3_N        J29   -5    D0360PA00X+005525Y+053450               S0      
317LAN1_P1_N        J29   -2    D0360PA00X+006525Y+054950               S0      
317LAN1_P2_P        J29   -3    D0360PA00X+005525Y+054450               S0      
317LAN1_P1_P        J29   -1    D0360PA00X+005525Y+055450               S0      
327N/C              U3    -4          A01X+007218Y+067571X0220Y0680R270 S2      
327GND              U3    -3          A01X+007218Y+068071X0220Y0680R270 S2      
317GND              VIA   -     D0100PA00X+006189Y+066601               S1      
317GND61            VIA   -     D0100PA00X+005712Y+067533               S1      
317GND29            VIA   -     D0100PA00X+005448Y+067981               S1      
317GND28            VIA   -     D0100PA00X+005924Y+067076               S1      
327GND              U3    -2          A01X+007218Y+068571X0220Y0680R270 S2      
327N42263600        U3    -1          A01X+007218Y+069071X0220Y0680R270 S2      
317GND              H2    -6    D0220PA00X+006535Y+080118               S0      
317GND              H2    -5    D0220PA00X+005551Y+080512               S0      
317GND              H2    -4    D0220PA00X+005157Y+081496               S0      
317GND              H2    -3    D0220PA00X+005551Y+082480               S0      
317GND              H2    -2    D0220PA00X+006535Y+082874               S0      
317N/C              H2    -1    D1580UA00X+006535Y+081496               S0      
327N/C                    -1          A01X+005634Y+087876X0390Y0390     S2      
327N/C                    -1          A08X+005516Y+088228X0390Y0390     S1      
317PSU5_AC_OK       VIA   -     D0100PA00X+007087Y+087228               S1      
317PSU6_AC_OK       VIA   -     D0100PA00X+007087Y+086628               S1      
317PSU4_DC_OK       VIA   -     D0100PA00X+007087Y+086028               S1      
317PSU2_PS_ON_N     VIA   -     D0100PA00X+007087Y+089775               S1      
317PSU4_AC_OK       VIA   -     D0100PA00X+007087Y+089012               S1      
327PSU_ALERT_N      R163  -2          A01X+005401Y+090420X0180Y0200R180 S2      
327T1_BLAD2_EN      R163  -1          A01X+005086Y+090420X0180Y0200R180 S2      
327TP_T4_BLAD4_EN   VIA   -           A01X+005115Y+096759X0300Y0300     S2      
327TP_T3_BLAD4_EN   VIA   -           A01X+005196Y+095320X0300Y0300     S2      
317NNAME10025       VIA   -     D0100PA00X+006082Y+101903               S3      
317NNAME10026       VIA   -     D0100PA00X+006358Y+101912               S3      
317GND              H4    -6    D0220PA00X+006535Y+115118               S0      
317GND              H4    -5    D0220PA00X+005551Y+115512               S0      
317GND              H4    -4    D0220PA00X+005157Y+116496               S0      
317N/C              H4    -1    D1580UA00X+006535Y+116496               S0      
317GND              H4    -3    D0220PA00X+005551Y+117480               S0      
317GND              H4    -2    D0220PA00X+006535Y+117874               S0      
327NNAME10014       VIA   -           A01X+005550Y+123574X0300Y0300     S2      
327GND              R140  -2          A01X+005441Y+125338X0180Y0200R180 S2      
327FAN_PWM          R140  -1          A01X+005126Y+125338X0180Y0200R180 S2      
327P12V             R144  -2          A01X+005421Y+126310X0180Y0200R180 S2      
327FAN3_TACH        R144  -1          A01X+005106Y+126310X0180Y0200R180 S2      
327P12V             R141  -2          A01X+005428Y+125763X0180Y0200R180 S2      
327FAN_PWM          R141  -1          A01X+005113Y+125763X0180Y0200R180 S2      
317P12V             VIA   -     D0100PA00X+005913Y+125765               S3      
317GND              VIA   -     D0100PA00X+005746Y+125338               S3      
327NNAME10015       VIA   -           A01X+005465Y+124474X0300Y0300     S2      
327P12V             R142  -2          A01X+005458Y+127978X0180Y0200R180 S2      
327FAN1_TACH        R142  -1          A01X+005143Y+127978X0180Y0200R180 S2      
327P12V             R143  -2          A01X+005455Y+126729X0180Y0200R180 S2      
327FAN2_TACH        R143  -1          A01X+005140Y+126729X0180Y0200R180 S2      
327P12V             R145  -2          A01X+005445Y+128404X0180Y0200R180 S2      
327FAN4_TACH        R145  -1          A01X+005130Y+128404X0180Y0200R180 S2      
327P12V             R146  -2          A01X+005458Y+127563X0180Y0200R180 S2      
327FAN5_TACH        R146  -1          A01X+005143Y+127563X0180Y0200R180 S2      
327P12V             R147  -2          A01X+005448Y+127154X0180Y0200R180 S2      
327FAN6_TACH        R147  -1          A01X+005133Y+127154X0180Y0200R180 S2      
317P12V             VIA   -     D0100PA00X+005836Y+127981               S3      
317P12V             VIA   -     D0100PA00X+005842Y+127238               S3      
327FRU_A1           R35   -2          A01X+005875Y+130275X0180Y0200R270 S2      
327P3V3             R35   -1          A01X+005875Y+129960X0180Y0200R270 S2      
327FRU_A2           R36   -2          A01X+005033Y+130268X0180Y0200R270 S2      
327P3V3             R36   -1          A01X+005033Y+129953X0180Y0200R270 S2      
327FRU_A0           R34   -2          A01X+007191Y+130258X0180Y0200R270 S2      
327P3V3             R34   -1          A01X+007191Y+129943X0180Y0200R270 S2      
327FRU_A0           R37   -2          A01X+006757Y+130258X0180Y0200R270 S2      
327GND              R37   -1          A01X+006757Y+129943X0180Y0200R270 S2      
327FRU_A1           R38   -2          A01X+006306Y+130275X0180Y0200R270 S2      
327GND              R38   -1          A01X+006306Y+129960X0180Y0200R270 S2      
327FRU_A2           R39   -2          A01X+005454Y+130268X0180Y0200R270 S2      
327GND              R39   -1          A01X+005454Y+129953X0180Y0200R270 S2      
317GND              VIA   -     D0100PA00X+005454Y+129651               S3      
317GND              VIA   -     D0100PA00X+006306Y+129631               S3      
317GND              VIA   -     D0100PA00X+006757Y+129665               S3      
317FRU_A1           VIA   -     D0100PA00X+006187Y+130919               S1      
317FRU_A2           VIA   -     D0100PA00X+005454Y+130900               S1      
317FRU_A0           VIA   -     D0100PA00X+006757Y+130783               S1      
327P3V3             U1    -8          A01X+007460Y+133320X0350Y0500R270 S2      
327FRU_WP           U1    -7          A01X+007460Y+132820X0350Y0500R270 S2      
327I2C_PDB_SCL      U1    -6          A01X+007460Y+132320X0350Y0500R270 S2      
327I2C_PDB_SDA      U1    -5          A01X+007460Y+131820X0350Y0500R270 S2      
327GND              U1    -4          A01X+005413Y+131820X0350Y0500R270 S2      
327FRU_A2           U1    -3          A01X+005413Y+132320X0350Y0500R270 S2      
327FRU_A1           U1    -2          A01X+005413Y+132820X0350Y0500R270 S2      
327FRU_A0           U1    -1          A01X+005413Y+133320X0350Y0500R270 S2      
317GND              VIA   -     D0100PA00X+005413Y+131376               S3      
317FRU_WP           VIA   -     D0100PA00X+007034Y+132820               S3      
327FRU_WP           R41   -2          A01X+005223Y+134197X0180Y0200R270 S2      
327P3V3             R41   -1          A01X+005223Y+133882X0180Y0200R270 S2      
317FRU_WP           VIA   -     D0100PA00X+006187Y+134210               S1      
317GND              H6    -6    D0220PA00X+006535Y+150118               S0      
317GND              H6    -5    D0220PA00X+005551Y+150512               S0      
317GND              H6    -4    D0220PA00X+005157Y+151496               S0      
317GND              H6    -3    D0220PA00X+005551Y+152480               S0      
317GND              H6    -2    D0220PA00X+006535Y+152874               S0      
317N/C              H6    -1    D1580UA00X+006535Y+151496               S0      
317LAN2_P4_N        J28   -8    D0360PA00X+006525Y+157750               S0      
317LAN2_P2_N        J28   -6    D0360PA00X+006525Y+158750               S0      
317LAN2_P3_P        J28   -4    D0360PA00X+006525Y+159750               S0      
317LAN2_P4_P        J28   -7    D0360PA00X+005525Y+158250               S0      
317LAN2_P3_N        J28   -5    D0360PA00X+005525Y+159250               S0      
317LAN2_P2_P        J28   -3    D0360PA00X+005525Y+160250               S0      
317LAN2_P1_N        J28   -2    D0360PA00X+006525Y+160750               S0      
317LAN2_P1_P        J28   -1    D0360PA00X+005525Y+161250               S0      
327GND              C87   -2          A01X+006029Y+177084X0440Y0540     S2      
327P12V             C87   -1          A01X+006777Y+177084X0440Y0540     S2      
327GND              C86   -2          A01X+006029Y+176298X0440Y0540     S2      
327P12V             C86   -1          A01X+006777Y+176298X0440Y0540     S2      
327GND              C85   -2          A01X+006029Y+175517X0440Y0540     S2      
327P12V             C85   -1          A01X+006777Y+175517X0440Y0540     S2      
317GND              VIA   -     D0100PA00X+005554Y+177084               S3      
317GND              VIA   -     D0100PA00X+005508Y+176298               S3      
317GND              VIA   -     D0100PA00X+005495Y+175517               S3      
327GND              C90   -2          A01X+005961Y+177837X0180Y0200     S2      
327P12V             C90   -1          A01X+006276Y+177837X0180Y0200     S2      
327N42241895        R154  -2          A01X+006264Y+178299X0180Y0200R180 S2      
327P12V             R154  -1          A01X+005949Y+178299X0180Y0200R180 S2      
327N42241895        U2    -1          A01X+007038Y+178054X0220Y0680     S2      
317GND              VIA   -     D0100PA00X+005643Y+177837               S3      
317GND              VIA   -     D0100PA00X+007038Y+179638               S3      
327N42241895        VIA   -           A01X+006436Y+178808X0300Y0300     S2      
327GND              U2    -8          A01X+007038Y+180134X0220Y0680     S2      
317GND              H8    -6    D0220PA00X+006535Y+185118               S0      
317GND              H8    -5    D0220PA00X+005551Y+185512               S0      
317GND              H8    -4    D0220PA00X+005157Y+186496               S0      
317N/C              H8    -1    D1580UA00X+006535Y+186496               S0      
317GND              H8    -3    D0220PA00X+005551Y+187480               S0      
317GND              H8    -2    D0220PA00X+006535Y+187874               S0      
317GND              VIA   -     D0100PA00X+007522Y+001875               S3      
317GND              VIA   -     D0100PA00X+009742Y+003285               S3      
317GND              VIA   -     D0100PA00X+009742Y+003744               S3      
317GND              H11   -7    D0220PA00X+007520Y+010512               S0      
317GND              H11   -9    D0220PA00X+007520Y+012480               S0      
317GND              H11   -8    D0220PA00X+007913Y+011496               S0      
317GND              VIA   -     D0100PA00X+009754Y+037658               S3      
317GND              VIA   -     D0100PA00X+009746Y+037191               S3      
317GND              VIA   -     D0100PA00X+009799Y+039122               S3      
317GND              VIA   -     D0100PA00X+009764Y+039602               S3      
317PSU2_AC_OK       VIA   -     D0100PA00X+009322Y+041774               S3      
317PSU2_DC_OK       VIA   -     D0100PA00X+009435Y+042156               S3      
317GND              H10   -8    D0220PA00X+007913Y+046496               S0      
317GND              H10   -7    D0220PA00X+007520Y+045512               S0      
317GND              H10   -9    D0220PA00X+007520Y+047480               S0      
327GND              U3    -6          A01X+009298Y+068071X0220Y0680R270 S2      
327N/C              U3    -5          A01X+009298Y+067571X0220Y0680R270 S2      
317GND              VIA   -     D0100PA00X+008619Y+068071               S3      
317GND              VIA   -     D0100PA00X+007952Y+068244               S3      
327N42263600        C92   -1          A01X+008736Y+070850X0280Y0320R090 S2      
327GND              C92   -2          A01X+008156Y+070850X0280Y0320R090 S2      
327GND              R160  -2          A01X+008868Y+070159X0180Y0200R270 S2      
327N42264085        R160  -1          A01X+008868Y+069844X0180Y0200R270 S2      
327PHLOSS           R161  -2          A01X+009286Y+069844X0180Y0200R090 S2      
327N42263600        R161  -1          A01X+009286Y+070159X0180Y0200R090 S2      
327N42263600        R158  -2          A01X+008027Y+070159X0180Y0200R270 S2      
327P12V             R158  -1          A01X+008027Y+069844X0180Y0200R270 S2      
327N42264085        R159  -2          A01X+008453Y+069844X0180Y0200R090 S2      
327N42263600        R159  -1          A01X+008453Y+070159X0180Y0200R090 S2      
327N42264085        U3    -8          A01X+009298Y+069071X0220Y0680R270 S2      
327GND              U3    -7          A01X+009298Y+068571X0220Y0680R270 S2      
317GND              VIA   -     D0100PA00X+008868Y+070411               S3      
317GND              VIA   -     D0100PA00X+008156Y+070544               S3      
317GND              VIA   -     D0100PA00X+008667Y+068571               S3      
317GND              VIA   -     D0100PA00X+007954Y+068571               S3      
317PHLOSS           VIA   -     D0100PA00X+009631Y+069662               S3      
327N42263600        VIA   -           A01X+009317Y+070633X0300Y0300     S2      
317GND              VIA   -     D0100PA00X+009859Y+072075               S3      
317GND              VIA   -     D0100PA00X+009856Y+071594               S3      
317GND              VIA   -     D0100PA00X+009744Y+073996               S3      
317GND              VIA   -     D0100PA00X+009753Y+073525               S3      
317GND              VIA   -     D0100PA00X+009812Y+074514               S3      
317PSU3_DC_OK       VIA   -     D0100PA00X+009578Y+075147               S1      
317GND              H2    -7    D0220PA00X+007520Y+080512               S0      
317GND              H2    -9    D0220PA00X+007520Y+082480               S0      
317GND              H2    -8    D0220PA00X+007913Y+081496               S0      
317PSU3_AC_OK       VIA   -     D0100PA00X+008934Y+087829               S1      
317I2C_PSU1_SCL     VIA   -     D0100PA00X+009173Y+089938               S1      
317I2C_PSU1_SDA     VIA   -     D0100PA00X+009263Y+090740               S1      
317PSU_ALERT_N      VIA   -     D0100PA00X+009129Y+092695               S1      
317I2C_PSU2_SDA     VIA   -     D0100PA00X+009814Y+099096               S1      
317NNAME10027       VIA   -     D0100PA00X+007645Y+101487               S3      
317NNAME10028       VIA   -     D0100PA00X+007950Y+101487               S3      
317GND              VIA   -     D0100PA00X+009690Y+106752               S3      
317T7_BLAD2_RXD     VIA   -     D0100PA00X+008276Y+106005               S1      
317GND              VIA   -     D0100PA00X+009695Y+109204               S3      
317GND              VIA   -     D0100PA00X+009695Y+108710               S3      
317GND              VIA   -     D0100PA00X+009677Y+107223               S3      
317P12V_STBY        VIA   -     D0100PA00X+009668Y+108179               S1      
317GND              H4    -8    D0220PA00X+007913Y+116496               S0      
317GND              H4    -7    D0220PA00X+007520Y+115512               S0      
317GND              H4    -9    D0220PA00X+007520Y+117480               S0      
327P3V3             VIA   -           A01X+008134Y+131070X0300Y0300     S2      
317T9_BLAD1_EN      VIA   -     D0100PA00X+009651Y+139538               S1      
317GND              VIA   -     D0100PA00X+009740Y+142434               S3      
317GND              VIA   -     D0100PA00X+009783Y+141949               S3      
317GND              VIA   -     D0100PA00X+009699Y+144374               S3      
317GND              VIA   -     D0100PA00X+009700Y+143898               S3      
317GND              VIA   -     D0100PA00X+009747Y+144792               S3      
317PSU_CSAHRE       VIA   -     D0100PA00X+009524Y+145332               S3      
317GND              H6    -7    D0220PA00X+007520Y+150512               S0      
317GND              H6    -9    D0220PA00X+007520Y+152480               S0      
317GND              H6    -8    D0220PA00X+007913Y+151496               S0      
327GND              C88   -2          A01X+008907Y+174823X0440Y0540R180 S2      
327N42242336        C88   -1          A01X+008159Y+174823X0440Y0540R180 S2      
327GND              C91   -2          A01X+008627Y+177110X0180Y0200R180 S2      
327P3V3_BUF         C91   -1          A01X+008312Y+177110X0180Y0200R180 S2      
327N42242090        R156  -2          A01X+008442Y+175490X0180Y0200R090 S2      
327P3V3_BUF         R156  -1          A01X+008442Y+175805X0180Y0200R090 S2      
327GND              R157  -2          A01X+008862Y+175805X0180Y0200R270 S2      
327N42242090        R157  -1          A01X+008862Y+175490X0180Y0200R270 S2      
327N42242336        R155  -2          A01X+008035Y+175490X0180Y0200R090 S2      
327P3V3_BUF         R155  -1          A01X+008035Y+175805X0180Y0200R090 S2      
327GND              C89   -2          A01X+008706Y+176419X0440Y0540R180 S2      
327P3V3_BUF         C89   -1          A01X+007958Y+176419X0440Y0540R180 S2      
317GND              VIA   -     D0100PA00X+008884Y+177110               S3      
317GND              VIA   -     D0100PA00X+009146Y+176506               S3      
317GND              VIA   -     D0100PA00X+009377Y+174823               S3      
327N42242336        VIA   -           A01X+007520Y+175057X0300Y0300     S2      
317P3V3_BUF         VIA   -     D0100PA00X+008038Y+177210               S3      
317P3V3_BUF         VIA   -     D0100PA00X+008038Y+176857               S3      
327N42242090        U2    -4          A01X+008538Y+178054X0220Y0680     S2      
327P3V3_BUF         U2    -3          A01X+008038Y+178054X0220Y0680     S2      
327P12V             U2    -2          A01X+007538Y+178054X0220Y0680     S2      
317GND              VIA   -     D0100PA00X+007538Y+179624               S3      
317GND              VIA   -     D0100PA00X+008038Y+179616               S3      
317GND              VIA   -     D0100PA00X+008538Y+179624               S3      
327N42242090        VIA   -           A01X+009203Y+177488X0300Y0300     S2      
317P3V3_BUF         VIA   -     D0100PA00X+008038Y+177561               S3      
327GND              U2    -7          A01X+007538Y+180134X0220Y0680     S2      
327GND              U2    -6          A01X+008038Y+180134X0220Y0680     S2      
327GND              U2    -5          A01X+008538Y+180134X0220Y0680     S2      
317GND              H8    -8    D0220PA00X+007913Y+186496               S0      
317GND              H8    -7    D0220PA00X+007520Y+185512               S0      
317GND              H8    -9    D0220PA00X+007520Y+187480               S0      
317GND              VIA   -     D0100PA00X+007683Y+206787               S3      
317PSU_ALERT_N      J1    -32   D0440PA00X+011992Y+001807               S0      
317PSU1_RESET       J1    -31   D0440PA00X+011992Y+002807               S0      
327GND              R45   -2          A01X+010585Y+002008X0180Y0200     S2      
327PSU1_RESET       R45   -1          A01X+010900Y+002008X0180Y0200     S2      
327P12V_STBY        R62   -2          A01X+010078Y+002832X0180Y0200     S2      
327PSU1_PS_KILL     R62   -1          A01X+010393Y+002832X0180Y0200     S2      
327P12V_STBY        R64   -2          A01X+010069Y+002420X0180Y0200     S2      
327PSU1_RESET       R64   -1          A01X+010384Y+002420X0180Y0200     S2      
327GND              R65   -2          A01X+010585Y+001585X0180Y0200     S2      
327PSU1_RESET       R65   -1          A01X+010900Y+001585X0180Y0200     S2      
317GND              VIA   -     D0100PA00X+010634Y+002258               S3      
317PSU1_RESET       VIA   -     D0100PA00X+010696Y+002629               S1      
317PSU1_PS_KILL     J1    -30   D0440PA00X+011992Y+003807               S0      
317PSU1_PS_ON_N     J1    -29   D0440PA00X+011992Y+004807               S0      
317PSU1_CSAHRE      J1    -28   D0440PA00X+011992Y+005807               S0      
327PSU1_PS_ON_N     R49   -2          A01X+010809Y+004629X0180Y0200R180 S2      
327GND              R49   -1          A01X+010494Y+004629X0180Y0200R180 S2      
327PSU2_PS_ON_N     R50   -2          A01X+010493Y+004180X0180Y0200     S2      
327GND              R50   -1          A01X+010808Y+004180X0180Y0200     S2      
327GND              R43   -2          A01X+010078Y+003285X0180Y0200     S2      
327PSU1_PS_KILL     R43   -1          A01X+010393Y+003285X0180Y0200     S2      
327GND              R63   -2          A01X+010078Y+003744X0180Y0200     S2      
327PSU1_PS_KILL     R63   -1          A01X+010393Y+003744X0180Y0200     S2      
317GND              VIA   -     D0100PA00X+010808Y+003890               S3      
317GND              VIA   -     D0100PA00X+010265Y+004946               S3      
317PSU2_PS_ON_N     VIA   -     D0100PA00X+010143Y+004180               S3      
317PSU1_PS_ON_N     VIA   -     D0100PA00X+010741Y+004990               S1      
317PSU1_PS_KILL     VIA   -     D0100PA00X+010704Y+003469               S1      
317PSU1_AC_OK       J1    -27   D0440PA00X+011992Y+006807               S0      
317PSU1_REMOTE_N    J1    -26   D0440PA00X+011992Y+007807               S0      
327GND              R5    -2          A01X+010414Y+007819X0180Y0200     S2      
327PSU1_REMOTE_N    R5    -1          A01X+010729Y+007819X0180Y0200     S2      
327PSU1_REMOTE_N    R87   -1          A01X+010727Y+007821X0180Y0200R270 S2      
327NNAME10029       R113  -2          A01X+010726Y+007506X0180Y0200R090 S2      
327PSU1_REMOTE_N    R113  -1          A01X+010726Y+007821X0180Y0200R090 S2      
327PSU_CSAHRE       R134  -2          A01X+010273Y+005825X0180Y0200     S2      
327PSU1_CSAHRE      R134  -1          A01X+010588Y+005825X0180Y0200     S2      
317PSU_CSAHRE       VIA   -     D0100PA00X+010435Y+006229               S3      
317NNAME10029       VIA   -     D0100PA00X+010726Y+007224               S3      
317PSU1_CSAHRE      VIA   -     D0100PA00X+010905Y+005825               S3      
317PHLOSS           J1    -25   D0440PA00X+011992Y+008807               S0      
317GND              J1    -24   D0440PA00X+011992Y+009807               S0      
327NNAME10030       R87   -2          A01X+010727Y+008136X0180Y0200R270 S2      
317GND              VIA   -     D0100PA00X+010412Y+008256               S3      
317NNAME10030       VIA   -     D0100PA00X+010867Y+008615               S3      
317GND              J1    -23   D0440PA00X+011992Y+010807               S0      
317GND              J1    -22   D0440PA00X+011992Y+011807               S0      
317GND              J1    -21   D0440PA00X+011992Y+012807               S0      
317GND              J1    -20   D0440PA00X+011992Y+013807               S0      
317GND              J1    -19   D0440PA00X+011992Y+014807               S0      
317GND              J1    -18   D0440PA00X+011992Y+015807               S0      
317GND              J1    -17   D0440PA00X+011992Y+016807               S0      
317GND              J1    -16   D0440PA00X+011992Y+017807               S0      
317GND              J1    -15   D0440PA00X+011992Y+018807               S0      
317GND              J1    -14   D0440PA00X+011992Y+019807               S0      
317GND              J1    -13   D0440PA00X+011992Y+020807               S0      
317P12V             J1    -12   D0440PA00X+011992Y+021807               S0      
317P12V             J1    -11   D0440PA00X+011992Y+022807               S0      
317P12V             J1    -10   D0440PA00X+011992Y+023807               S0      
317P12V             J1    -9    D0440PA00X+011992Y+024807               S0      
317P12V             J1    -8    D0440PA00X+011992Y+025807               S0      
317P12V             J1    -7    D0440PA00X+011992Y+026807               S0      
317P12V             J1    -6    D0440PA00X+011992Y+027807               S0      
317P12V             J1    -5    D0440PA00X+011992Y+028807               S0      
317P12V             J1    -4    D0440PA00X+011992Y+029807               S0      
317P12V             J1    -3    D0440PA00X+011992Y+030807               S0      
317P12V             J1    -2    D0440PA00X+011992Y+031807               S0      
317P12V             J1    -1    D0440PA00X+011992Y+032807               S0      
317PSU_ALERT_N      J2    -32   D0440PA00X+011992Y+036610               S0      
317PSU2_RESET       J2    -31   D0440PA00X+011992Y+037610               S0      
317PSU2_PS_KILL     J2    -30   D0440PA00X+011992Y+038610               S0      
317PSU2_PS_ON_N     J2    -29   D0440PA00X+011992Y+039610               S0      
327GND              R46   -2          A01X+010052Y+039122X0180Y0200     S2      
327PSU2_PS_KILL     R46   -1          A01X+010367Y+039122X0180Y0200     S2      
327GND              R47   -2          A01X+010052Y+037658X0180Y0200     S2      
327PSU2_RESET       R47   -1          A01X+010367Y+037658X0180Y0200     S2      
327P12V_STBY        R66   -2          A01X+010052Y+038624X0180Y0200     S2      
327PSU2_PS_KILL     R66   -1          A01X+010367Y+038624X0180Y0200     S2      
327P12V_STBY        R68   -2          A01X+010052Y+038139X0180Y0200     S2      
327PSU2_RESET       R68   -1          A01X+010367Y+038139X0180Y0200     S2      
327GND              R69   -2          A01X+010052Y+037191X0180Y0200     S2      
327PSU2_RESET       R69   -1          A01X+010367Y+037191X0180Y0200     S2      
317PSU2_RESET       VIA   -     D0100PA00X+010684Y+037646               S1      
317PSU2_PS_KILL     VIA   -     D0100PA00X+010671Y+039122               S1      
317PSU2_CSAHRE      J2    -28   D0440PA00X+011992Y+040610               S0      
317PSU2_AC_OK       J2    -27   D0440PA00X+011992Y+041610               S0      
327GND              R67   -2          A01X+010052Y+039602X0180Y0200     S2      
327PSU2_PS_KILL     R67   -1          A01X+010367Y+039602X0180Y0200     S2      
327PSU_CSAHRE       R135  -2          A01X+010079Y+040035X0180Y0200     S2      
327PSU2_CSAHRE      R135  -1          A01X+010394Y+040035X0180Y0200     S2      
317PSU_CSAHRE       VIA   -     D0100PA00X+010545Y+040680               S3      
317PSU2_PS_ON_N     VIA   -     D0100PA00X+011450Y+039621               S3      
317PSU2_REMOTE_N    J2    -26   D0440PA00X+011992Y+042610               S0      
317PHLOSS           J2    -25   D0440PA00X+011992Y+043610               S0      
327GND              R7    -2          A01X+010452Y+042610X0180Y0200     S2      
327PSU2_REMOTE_N    R7    -1          A01X+010767Y+042610X0180Y0200     S2      
327NNAME10031       R93   -2          A01X+010767Y+042925X0180Y0200R270 S2      
327PSU2_REMOTE_N    R93   -1          A01X+010767Y+042610X0180Y0200R270 S2      
327NNAME10032       R117  -2          A01X+010767Y+042295X0180Y0200R090 S2      
327PSU2_REMOTE_N    R117  -1          A01X+010767Y+042610X0180Y0200R090 S2      
317GND              VIA   -     D0100PA00X+010199Y+042610               S3      
317NNAME10031       VIA   -     D0100PA00X+010948Y+043474               S3      
317NNAME10032       VIA   -     D0100PA00X+011102Y+041957               S3      
317GND              J2    -24   D0440PA00X+011992Y+044610               S0      
317GND              J2    -23   D0440PA00X+011992Y+045610               S0      
317GND              J2    -22   D0440PA00X+011992Y+046610               S0      
317GND              J2    -21   D0440PA00X+011992Y+047610               S0      
317GND              J2    -20   D0440PA00X+011992Y+048610               S0      
317GND              J2    -19   D0440PA00X+011992Y+049610               S0      
317GND              J2    -18   D0440PA00X+011992Y+050610               S0      
317GND              J2    -17   D0440PA00X+011992Y+051610               S0      
317GND              J2    -16   D0440PA00X+011992Y+052610               S0      
317GND              J2    -15   D0440PA00X+011992Y+053610               S0      
317GND              J2    -14   D0440PA00X+011992Y+054610               S0      
317GND              J2    -13   D0440PA00X+011992Y+055610               S0      
317P12V             J2    -12   D0440PA00X+011992Y+056610               S0      
317P12V             J2    -11   D0440PA00X+011992Y+057610               S0      
317P12V             J2    -10   D0440PA00X+011992Y+058610               S0      
317P12V             J2    -9    D0440PA00X+011992Y+059610               S0      
317P12V             J2    -8    D0440PA00X+011992Y+060610               S0      
317P12V             J2    -7    D0440PA00X+011992Y+061610               S0      
317P12V             J2    -6    D0440PA00X+011992Y+062610               S0      
317P12V             J2    -5    D0440PA00X+011992Y+063610               S0      
317P12V             J2    -4    D0440PA00X+011992Y+064610               S0      
317P12V             J2    -3    D0440PA00X+011992Y+065610               S0      
317P12V             J2    -2    D0440PA00X+011992Y+066610               S0      
317P12V             J2    -1    D0440PA00X+011992Y+067610               S0      
317PHLOSS           VIA   -     D0100PA00X+010296Y+067282               S3      
317PHLOSS           VIA   -     D0100PA00X+011302Y+070636               S3      
327N42264085        VIA   -           A01X+010060Y+069071X0300Y0300     S2      
317PSU_ALERT_N      J3    -32   D0440PA00X+011992Y+071413               S0      
317PSU3_RESET       J3    -31   D0440PA00X+011992Y+072413               S0      
317PSU3_PS_KILL     J3    -30   D0440PA00X+011992Y+073413               S0      
327GND              R55   -2          A01X+010106Y+072075X0180Y0200     S2      
327PSU3_RESET       R55   -1          A01X+010421Y+072075X0180Y0200     S2      
327P12V_STBY        R70   -2          A01X+010106Y+073040X0180Y0200     S2      
327PSU3_PS_KILL     R70   -1          A01X+010421Y+073040X0180Y0200     S2      
327P12V_STBY        R72   -2          A01X+010106Y+072546X0180Y0200     S2      
327PSU3_RESET       R72   -1          A01X+010421Y+072546X0180Y0200     S2      
327GND              R73   -2          A01X+010106Y+071594X0180Y0200     S2      
327PSU3_RESET       R73   -1          A01X+010421Y+071594X0180Y0200     S2      
317PSU3_RESET       VIA   -     D0100PA00X+010703Y+072537               S1      
317PSU3_PS_ON_N     J3    -29   D0440PA00X+011992Y+074413               S0      
317PSU3_CSAHRE      J3    -28   D0440PA00X+011992Y+075413               S0      
327PSU3_PS_ON_N     R51   -2          A01X+010435Y+074514X0180Y0200R180 S2      
327GND              R51   -1          A01X+010120Y+074514X0180Y0200R180 S2      
327GND              R48   -2          A01X+010106Y+073525X0180Y0200     S2      
327PSU3_PS_KILL     R48   -1          A01X+010421Y+073525X0180Y0200     S2      
327GND              R71   -2          A01X+010106Y+073996X0180Y0200     S2      
327PSU3_PS_KILL     R71   -1          A01X+010421Y+073996X0180Y0200     S2      
327PSU_CSAHRE       R136  -2          A01X+010152Y+074948X0180Y0200     S2      
327PSU3_CSAHRE      R136  -1          A01X+010467Y+074948X0180Y0200     S2      
317PSU_CSAHRE       VIA   -     D0100PA00X+010509Y+075413               S3      
317PSU3_PS_ON_N     VIA   -     D0100PA00X+010694Y+074514               S1      
317PSU3_PS_KILL     VIA   -     D0100PA00X+010717Y+073522               S1      
317PSU3_AC_OK       J3    -27   D0440PA00X+011992Y+076413               S0      
317PSU3_REMOTE_N    J3    -26   D0440PA00X+011992Y+077413               S0      
327GND              R6    -2          A01X+010444Y+077410X0180Y0200     S2      
327PSU3_REMOTE_N    R6    -1          A01X+010759Y+077410X0180Y0200     S2      
327NNAME10033       R97   -2          A01X+010762Y+077730X0180Y0200R270 S2      
327PSU3_REMOTE_N    R97   -1          A01X+010762Y+077415X0180Y0200R270 S2      
327NNAME10034       R121  -2          A01X+010762Y+077100X0180Y0200R090 S2      
327PSU3_REMOTE_N    R121  -1          A01X+010762Y+077415X0180Y0200R090 S2      
317GND              VIA   -     D0100PA00X+010124Y+077410               S3      
317NNAME10034       VIA   -     D0100PA00X+011284Y+076912               S3      
317PHLOSS           J3    -25   D0440PA00X+011992Y+078413               S0      
317GND              J3    -24   D0440PA00X+011992Y+079413               S0      
317GND              J3    -23   D0440PA00X+011992Y+080413               S0      
317NNAME10033       VIA   -     D0100PA00X+011197Y+079526               S3      
317GND              J3    -22   D0440PA00X+011992Y+081413               S0      
317GND              J3    -21   D0440PA00X+011992Y+082413               S0      
317GND              J3    -20   D0440PA00X+011992Y+083413               S0      
317GND              J3    -19   D0440PA00X+011992Y+084413               S0      
317GND              J3    -18   D0440PA00X+011992Y+085413               S0      
317PHLOSS           VIA   -     D0100PA00X+011514Y+084924               S3      
317GND              J3    -17   D0440PA00X+011992Y+086413               S0      
317GND              J3    -16   D0440PA00X+011992Y+087413               S0      
317GND              J3    -15   D0440PA00X+011992Y+088413               S0      
317GND              J3    -14   D0440PA00X+011992Y+089413               S0      
317GND              J3    -13   D0440PA00X+011992Y+090413               S0      
317P12V             J3    -12   D0440PA00X+011992Y+091413               S0      
317P12V             J3    -11   D0440PA00X+011992Y+092413               S0      
317P12V             J3    -10   D0440PA00X+011992Y+093413               S0      
317P12V             J3    -9    D0440PA00X+011992Y+094413               S0      
317P12V             J3    -8    D0440PA00X+011992Y+095413               S0      
317P12V             J3    -7    D0440PA00X+011992Y+096413               S0      
317P12V             J3    -6    D0440PA00X+011992Y+097413               S0      
317NNAME10035       VIA   -     D0100PA00X+010540Y+097204               S3      
317NNAME10033       VIA   -     D0100PA00X+010261Y+097222               S3      
317P12V             J3    -5    D0440PA00X+011992Y+098413               S0      
317P12V             J3    -4    D0440PA00X+011992Y+099413               S0      
317P12V             J3    -3    D0440PA00X+011992Y+100413               S0      
317P12V             J3    -2    D0440PA00X+011992Y+101413               S0      
317P12V             J3    -1    D0440PA00X+011992Y+102413               S0      
317I2C_PSU2_SCL     VIA   -     D0100PA00X+010069Y+099939               S1      
317PSU_ALERT_N      J4    -32   D0440PA00X+011992Y+106217               S0      
317PSU4_RESET       J4    -31   D0440PA00X+011992Y+107217               S0      
327GND              R77   -2          A01X+010119Y+106752X0180Y0200     S2      
327PSU4_RESET       R77   -1          A01X+010434Y+106752X0180Y0200     S2      
317PSU4_PS_KILL     J4    -30   D0440PA00X+011992Y+108217               S0      
317PSU4_PS_ON_N     J4    -29   D0440PA00X+011992Y+109217               S0      
327GND              R56   -2          A01X+010119Y+109204X0180Y0200     S2      
327PSU4_PS_KILL     R56   -1          A01X+010434Y+109204X0180Y0200     S2      
327GND              R57   -2          A01X+010119Y+107223X0180Y0200     S2      
327PSU4_RESET       R57   -1          A01X+010434Y+107223X0180Y0200     S2      
327P12V_STBY        R74   -2          A01X+010119Y+108179X0180Y0200     S2      
327PSU4_PS_KILL     R74   -1          A01X+010434Y+108179X0180Y0200     S2      
327P12V_STBY        R76   -2          A01X+010119Y+107690X0180Y0200     S2      
327PSU4_RESET       R76   -1          A01X+010434Y+107690X0180Y0200     S2      
327GND              R75   -2          A01X+010119Y+108710X0180Y0200     S2      
327PSU4_PS_KILL     R75   -1          A01X+010434Y+108710X0180Y0200     S2      
317PSU4_PS_ON_N     VIA   -     D0100PA00X+010735Y+109348               S1      
317PSU4_PS_KILL     VIA   -     D0100PA00X+010724Y+108179               S1      
317PSU4_RESET       VIA   -     D0100PA00X+010722Y+107221               S1      
317PSU4_CSAHRE      J4    -28   D0440PA00X+011992Y+110217               S0      
317PSU4_AC_OK       J4    -27   D0440PA00X+011992Y+111217               S0      
317PSU4_REMOTE_N    J4    -26   D0440PA00X+011992Y+112217               S0      
327PSU4_PS_ON_N     R52   -2          A01X+010443Y+109640X0180Y0200R180 S2      
327GND              R52   -1          A01X+010128Y+109640X0180Y0200R180 S2      
327NNAME10036       R125  -2          A01X+010882Y+111902X0180Y0200R090 S2      
327PSU_CSAHRE       R137  -2          A01X+010588Y+110254X0180Y0200     S2      
327PSU4_CSAHRE      R137  -1          A01X+010903Y+110254X0180Y0200     S2      
317GND              VIA   -     D0100PA00X+009865Y+109640               S3      
317PSU_CSAHRE       VIA   -     D0100PA00X+010878Y+110576               S3      
317MATE_A1          VIA   -     D0100PA00X+010515Y+111838               S1      
317NNAME10036       VIA   -     D0100PA00X+011250Y+111586               S3      
317PHLOSS           J4    -25   D0440PA00X+011992Y+113217               S0      
317GND              J4    -24   D0440PA00X+011992Y+114217               S0      
327GND              R20   -2          A01X+010568Y+112217X0180Y0200     S2      
327PSU4_REMOTE_N    R20   -1          A01X+010883Y+112217X0180Y0200     S2      
327NNAME10028       R109  -2          A01X+010882Y+112531X0180Y0200R270 S2      
327PSU4_REMOTE_N    R109  -1          A01X+010882Y+112216X0180Y0200R270 S2      
327PSU4_REMOTE_N    R125  -1          A01X+010882Y+112217X0180Y0200R090 S2      
317GND              VIA   -     D0100PA00X+010568Y+112592               S3      
317NNAME10028       VIA   -     D0100PA00X+010847Y+112929               S3      
317GND              J4    -23   D0440PA00X+011992Y+115217               S0      
317GND              J4    -22   D0440PA00X+011992Y+116217               S0      
317GND              J4    -21   D0440PA00X+011992Y+117217               S0      
317GND              J4    -20   D0440PA00X+011992Y+118217               S0      
317GND              J4    -19   D0440PA00X+011992Y+119217               S0      
317GND              J4    -18   D0440PA00X+011992Y+120217               S0      
317GND              J4    -17   D0440PA00X+011992Y+121217               S0      
317GND              J4    -16   D0440PA00X+011992Y+122217               S0      
317GND              J4    -15   D0440PA00X+011992Y+123217               S0      
317GND              J4    -14   D0440PA00X+011992Y+124217               S0      
317GND              J4    -13   D0440PA00X+011992Y+125217               S0      
317P12V             J4    -12   D0440PA00X+011992Y+126217               S0      
317P12V             J4    -11   D0440PA00X+011992Y+127217               S0      
317P12V             J4    -10   D0440PA00X+011992Y+128217               S0      
317P12V             J4    -9    D0440PA00X+011992Y+129217               S0      
317P12V             J4    -8    D0440PA00X+011992Y+130217               S0      
317P12V             J4    -7    D0440PA00X+011992Y+131217               S0      
317PSU_CSAHRE       VIA   -     D0100PA00X+010072Y+131281               S1      
317PSU6_DC_OK       VIA   -     D0100PA00X+010072Y+130681               S1      
317P12V             J4    -6    D0440PA00X+011992Y+132217               S0      
317P12V             J4    -5    D0440PA00X+011992Y+133217               S0      
317I2C_PSU3_SDA     VIA   -     D0100PA00X+010072Y+133081               S1      
317I2C_PSU3_SCL     VIA   -     D0100PA00X+010072Y+133681               S1      
317PSU_ALERT_N      VIA   -     D0100PA00X+010072Y+132481               S1      
317PSU5_DC_OK       VIA   -     D0100PA00X+010072Y+131881               S1      
317P12V             J4    -4    D0440PA00X+011992Y+134217               S0      
317P12V             J4    -3    D0440PA00X+011992Y+135217               S0      
317P12V             J4    -2    D0440PA00X+011992Y+136217               S0      
317PSU_CSAHRE       VIA   -     D0100PA00X+010072Y+134607               S1      
317P12V             J4    -1    D0440PA00X+011992Y+137217               S0      
317PSU_ALERT_N      J5    -32   D0440PA00X+011992Y+141020               S0      
317PSU5_RESET       J5    -31   D0440PA00X+011992Y+142020               S0      
317PSU5_PS_KILL     J5    -30   D0440PA00X+011992Y+143020               S0      
327GND              R59   -2          A01X+010023Y+141949X0180Y0200     S2      
327PSU5_RESET       R59   -1          A01X+010338Y+141949X0180Y0200     S2      
327P12V_STBY        R80   -2          A01X+010023Y+142920X0180Y0200     S2      
327PSU5_RESET       R80   -1          A01X+010338Y+142920X0180Y0200     S2      
327GND              R81   -2          A01X+010023Y+142434X0180Y0200     S2      
327PSU5_RESET       R81   -1          A01X+010338Y+142434X0180Y0200     S2      
317PSU5_PS_KILL     VIA   -     D0100PA00X+010696Y+143404               S1      
317PSU5_RESET       VIA   -     D0100PA00X+010692Y+141949               S1      
317PSU5_PS_ON_N     J5    -29   D0440PA00X+011992Y+144020               S0      
317PSU5_CSAHRE      J5    -28   D0440PA00X+011992Y+145020               S0      
317PSU5_AC_OK       J5    -27   D0440PA00X+011992Y+146020               S0      
327PSU5_PS_ON_N     R53   -2          A01X+010344Y+144792X0180Y0200R180 S2      
327GND              R53   -1          A01X+010029Y+144792X0180Y0200R180 S2      
327GND              R58   -2          A01X+010023Y+144374X0180Y0200     S2      
327PSU5_PS_KILL     R58   -1          A01X+010338Y+144374X0180Y0200     S2      
327P12V_STBY        R78   -2          A01X+010023Y+143404X0180Y0200     S2      
327PSU5_PS_KILL     R78   -1          A01X+010338Y+143404X0180Y0200     S2      
327GND              R79   -2          A01X+010023Y+143898X0180Y0200     S2      
327PSU5_PS_KILL     R79   -1          A01X+010338Y+143898X0180Y0200     S2      
327PSU_CSAHRE       R138  -2          A01X+010002Y+145313X0180Y0200     S2      
327PSU5_CSAHRE      R138  -1          A01X+010317Y+145313X0180Y0200     S2      
317PSU5_PS_ON_N     VIA   -     D0100PA00X+010676Y+144460               S1      
317PSU5_CSAHRE      VIA   -     D0100PA00X+010701Y+145265               S1      
317PSU5_REMOTE_N    J5    -26   D0440PA00X+011992Y+147020               S0      
317PHLOSS           J5    -25   D0440PA00X+011992Y+148020               S0      
327GND              R19   -2          A01X+010539Y+147021X0180Y0200     S2      
327PSU5_REMOTE_N    R19   -1          A01X+010854Y+147021X0180Y0200     S2      
327NNAME10037       R105  -2          A01X+010857Y+147336X0180Y0200R270 S2      
327PSU5_REMOTE_N    R105  -1          A01X+010857Y+147021X0180Y0200R270 S2      
327NNAME10038       R129  -2          A01X+010857Y+146706X0180Y0200R090 S2      
327PSU5_REMOTE_N    R129  -1          A01X+010857Y+147021X0180Y0200R090 S2      
317GND              VIA   -     D0100PA00X+010546Y+147289               S3      
317NNAME10038       VIA   -     D0100PA00X+010857Y+146339               S3      
317GND              J5    -24   D0440PA00X+011992Y+149020               S0      
317GND              J5    -23   D0440PA00X+011992Y+150020               S0      
317NNAME10037       VIA   -     D0100PA00X+011352Y+148957               S3      
317GND              J5    -22   D0440PA00X+011992Y+151020               S0      
317GND              J5    -21   D0440PA00X+011992Y+152020               S0      
317GND              J5    -20   D0440PA00X+011992Y+153020               S0      
317GND              J5    -19   D0440PA00X+011992Y+154020               S0      
317GND              J5    -18   D0440PA00X+011992Y+155020               S0      
317GND              J5    -17   D0440PA00X+011992Y+156020               S0      
317GND              J5    -16   D0440PA00X+011992Y+157020               S0      
317GND              J5    -15   D0440PA00X+011992Y+158020               S0      
317GND              J5    -14   D0440PA00X+011992Y+159020               S0      
317GND              J5    -13   D0440PA00X+011992Y+160020               S0      
317P12V             J5    -12   D0440PA00X+011992Y+161020               S0      
317P12V             J5    -11   D0440PA00X+011992Y+162020               S0      
317P12V             J5    -10   D0440PA00X+011992Y+163020               S0      
317P12V             J5    -9    D0440PA00X+011992Y+164020               S0      
317P12V             J5    -8    D0440PA00X+011992Y+165020               S0      
317P12V             J5    -7    D0440PA00X+011992Y+166020               S0      
317P12V             J5    -6    D0440PA00X+011992Y+167020               S0      
317P12V             J5    -5    D0440PA00X+011992Y+168020               S0      
317P12V             J5    -4    D0440PA00X+011992Y+169020               S0      
317P12V             J5    -3    D0440PA00X+011992Y+170020               S0      
317P12V             J5    -2    D0440PA00X+011992Y+171020               S0      
317P12V             J5    -1    D0440PA00X+011992Y+172020               S0      
317PSU_ALERT_N      J6    -32   D0440PA00X+011992Y+175823               S0      
317PSU6_RESET       J6    -31   D0440PA00X+011992Y+176823               S0      
327GND              R61   -2          A01X+010168Y+176083X0180Y0200     S2      
327PSU6_RESET       R61   -1          A01X+010483Y+176083X0180Y0200     S2      
327P12V_STBY        R84   -2          A01X+010168Y+177053X0180Y0200     S2      
327PSU6_RESET       R84   -1          A01X+010483Y+177053X0180Y0200     S2      
327GND              R85   -2          A01X+010168Y+176572X0180Y0200     S2      
327PSU6_RESET       R85   -1          A01X+010483Y+176572X0180Y0200     S2      
317GND              VIA   -     D0100PA00X+009910Y+176572               S3      
317GND              VIA   -     D0100PA00X+009907Y+176083               S3      
317PSU6_RESET       VIA   -     D0100PA00X+010736Y+177044               S1      
317PSU6_PS_KILL     J6    -30   D0440PA00X+011992Y+177823               S0      
317PSU6_PS_ON_N     J6    -29   D0440PA00X+011992Y+178823               S0      
317PSU6_CSAHRE      J6    -28   D0440PA00X+011992Y+179823               S0      
327PSU6_PS_ON_N     R54   -2          A01X+010493Y+178995X0180Y0200R180 S2      
327GND              R54   -1          A01X+010178Y+178995X0180Y0200R180 S2      
327GND              R60   -2          A01X+010168Y+178557X0180Y0200     S2      
327PSU6_PS_KILL     R60   -1          A01X+010483Y+178557X0180Y0200     S2      
327P12V_STBY        R82   -2          A01X+010168Y+177551X0180Y0200     S2      
327PSU6_PS_KILL     R82   -1          A01X+010483Y+177551X0180Y0200     S2      
327GND              R83   -2          A01X+010168Y+178054X0180Y0200     S2      
327PSU6_PS_KILL     R83   -1          A01X+010483Y+178054X0180Y0200     S2      
317GND              VIA   -     D0100PA00X+009905Y+178557               S3      
317GND              VIA   -     D0100PA00X+009887Y+178054               S3      
317GND              VIA   -     D0100PA00X+009929Y+178995               S3      
317PSU_CSAHRE       VIA   -     D0100PA00X+010739Y+179446               S3      
317PSU6_PS_ON_N     VIA   -     D0100PA00X+010722Y+179159               S1      
317PSU6_PS_KILL     VIA   -     D0100PA00X+010737Y+178054               S1      
317PSU6_AC_OK       J6    -27   D0440PA00X+011992Y+180823               S0      
317PSU6_REMOTE_N    J6    -26   D0440PA00X+011992Y+181823               S0      
327GND              R22   -2          A01X+010567Y+181823X0180Y0200     S2      
327PSU6_REMOTE_N    R22   -1          A01X+010882Y+181823X0180Y0200     S2      
327PSU6_REMOTE_N    R101  -1          A01X+010882Y+181823X0180Y0200R270 S2      
327NNAME10039       R133  -2          A01X+010882Y+181508X0180Y0200R090 S2      
327PSU6_REMOTE_N    R133  -1          A01X+010882Y+181823X0180Y0200R090 S2      
327PSU_CSAHRE       R139  -2          A01X+010367Y+179822X0180Y0200     S2      
327PSU6_CSAHRE      R139  -1          A01X+010682Y+179822X0180Y0200     S2      
317GND              VIA   -     D0100PA00X+010567Y+181523               S3      
317NNAME10039       VIA   -     D0100PA00X+010882Y+181212               S3      
317PSU6_CSAHRE      VIA   -     D0100PA00X+010682Y+180223               S1      
317PHLOSS           J6    -25   D0440PA00X+011992Y+182823               S0      
317GND              J6    -24   D0440PA00X+011992Y+183823               S0      
327NNAME10026       R101  -2          A01X+010882Y+182138X0180Y0200R270 S2      
317NNAME10026       VIA   -     D0100PA00X+010882Y+182447               S3      
317GND              J6    -23   D0440PA00X+011992Y+184823               S0      
317GND              J6    -22   D0440PA00X+011992Y+185823               S0      
317GND              J6    -21   D0440PA00X+011992Y+186823               S0      
317GND              J6    -20   D0440PA00X+011992Y+187823               S0      
317GND              J6    -19   D0440PA00X+011992Y+188823               S0      
317GND              J6    -18   D0440PA00X+011992Y+189823               S0      
317GND              J6    -17   D0440PA00X+011992Y+190823               S0      
317GND              J6    -16   D0440PA00X+011992Y+191823               S0      
317GND              J6    -15   D0440PA00X+011992Y+192823               S0      
317GND              J6    -14   D0440PA00X+011992Y+193823               S0      
317GND              J6    -13   D0440PA00X+011992Y+194823               S0      
317P12V             J6    -12   D0440PA00X+011992Y+195823               S0      
317P12V             J6    -11   D0440PA00X+011992Y+196823               S0      
317P12V             J6    -10   D0440PA00X+011992Y+197823               S0      
317P12V             J6    -9    D0440PA00X+011992Y+198823               S0      
317P12V             J6    -8    D0440PA00X+011992Y+199823               S0      
317P12V             J6    -7    D0440PA00X+011992Y+200823               S0      
317P12V             J6    -6    D0440PA00X+011992Y+201823               S0      
317P12V             J6    -5    D0440PA00X+011992Y+202823               S0      
317P12V             J6    -4    D0440PA00X+011992Y+203823               S0      
317P12V             J6    -3    D0440PA00X+011992Y+204823               S0      
317P12V             J6    -2    D0440PA00X+011992Y+205823               S0      
317P12V             J6    -1    D0440PA00X+011992Y+206823               S0      
317GND              VIA   -     D0100PA00X+010999Y+208361               S3      
317GND              VIA   -     D0100PA00X+012522Y+000300               S3      
317N/C              J1    -34   D0440PA00X+013992Y+002807               S0      
317I2C_PSU1_SDA     J1    -33   D0440PA00X+013992Y+001807               S0      
317PSU1_DC_OK       J1    -37   D0440PA00X+013992Y+005807               S0      
317PSU1_RETURN      J1    -36   D0440PA00X+013992Y+004807               S0      
317I2C_PSU1_SCL     J1    -35   D0440PA00X+013992Y+003807               S0      
317P12V_STBY        J1    -39   D0440PA00X+013992Y+007807               S0      
317PSU1_AD0         J1    -38   D0440PA00X+013992Y+006807               S0      
317GND              J1    -41   D0440PA00X+013992Y+009807               S0      
317PSU1_REMOTE_P    J1    -40   D0440PA00X+013992Y+008807               S0      
317GND              J1    -44   D0440PA00X+013992Y+012807               S0      
317GND              J1    -43   D0440PA00X+013992Y+011807               S0      
317GND              J1    -42   D0440PA00X+013992Y+010807               S0      
317GND              J1    -46   D0440PA00X+013992Y+014807               S0      
317GND              J1    -45   D0440PA00X+013992Y+013807               S0      
317GND              J1    -49   D0440PA00X+013992Y+017807               S0      
317GND              J1    -48   D0440PA00X+013992Y+016807               S0      
317GND              J1    -47   D0440PA00X+013992Y+015807               S0      
317GND              J1    -51   D0440PA00X+013992Y+019807               S0      
317GND              J1    -50   D0440PA00X+013992Y+018807               S0      
317P12V             J1    -54   D0440PA00X+013992Y+022807               S0      
317P12V             J1    -53   D0440PA00X+013992Y+021807               S0      
317GND              J1    -52   D0440PA00X+013992Y+020807               S0      
317P12V             J1    -56   D0440PA00X+013992Y+024807               S0      
317P12V             J1    -55   D0440PA00X+013992Y+023807               S0      
317P12V             J1    -58   D0440PA00X+013992Y+026807               S0      
317P12V             J1    -57   D0440PA00X+013992Y+025807               S0      
317P12V             J1    -61   D0440PA00X+013992Y+029807               S0      
317P12V             J1    -60   D0440PA00X+013992Y+028807               S0      
317P12V             J1    -59   D0440PA00X+013992Y+027807               S0      
317P12V             J1    -63   D0440PA00X+013992Y+031807               S0      
317P12V             J1    -62   D0440PA00X+013992Y+030807               S0      
317P12V             J1    -64   D0440PA00X+013992Y+032807               S0      
317I2C_PSU1_SDA     J2    -33   D0440PA00X+013992Y+036610               S0      
317PSU2_RETURN      J2    -36   D0440PA00X+013992Y+039610               S0      
317I2C_PSU1_SCL     J2    -35   D0440PA00X+013992Y+038610               S0      
317N/C              J2    -34   D0440PA00X+013992Y+037610               S0      
317PSU2_AD0         J2    -38   D0440PA00X+013992Y+041610               S0      
317PSU2_DC_OK       J2    -37   D0440PA00X+013992Y+040610               S0      
317PSU2_REMOTE_P    J2    -40   D0440PA00X+013992Y+043610               S0      
317P12V_STBY        J2    -39   D0440PA00X+013992Y+042610               S0      
317GND              J2    -43   D0440PA00X+013992Y+046610               S0      
317GND              J2    -42   D0440PA00X+013992Y+045610               S0      
317GND              J2    -41   D0440PA00X+013992Y+044610               S0      
317GND              J2    -45   D0440PA00X+013992Y+048610               S0      
317GND              J2    -44   D0440PA00X+013992Y+047610               S0      
317GND              J2    -48   D0440PA00X+013992Y+051610               S0      
317GND              J2    -47   D0440PA00X+013992Y+050610               S0      
317GND              J2    -46   D0440PA00X+013992Y+049610               S0      
317GND              J2    -50   D0440PA00X+013992Y+053610               S0      
317GND              J2    -49   D0440PA00X+013992Y+052610               S0      
317P12V             J2    -53   D0440PA00X+013992Y+056610               S0      
317GND              J2    -52   D0440PA00X+013992Y+055610               S0      
317GND              J2    -51   D0440PA00X+013992Y+054610               S0      
317P12V             J2    -55   D0440PA00X+013992Y+058610               S0      
317P12V             J2    -54   D0440PA00X+013992Y+057610               S0      
317P12V             J2    -57   D0440PA00X+013992Y+060610               S0      
317P12V             J2    -56   D0440PA00X+013992Y+059610               S0      
317P12V             J2    -60   D0440PA00X+013992Y+063610               S0      
317P12V             J2    -59   D0440PA00X+013992Y+062610               S0      
317P12V             J2    -58   D0440PA00X+013992Y+061610               S0      
317P12V             J2    -62   D0440PA00X+013992Y+065610               S0      
317P12V             J2    -61   D0440PA00X+013992Y+064610               S0      
317P12V             J2    -64   D0440PA00X+013992Y+067610               S0      
317P12V             J2    -63   D0440PA00X+013992Y+066610               S0      
317I2C_PSU2_SCL     J3    -35   D0440PA00X+013992Y+073413               S0      
317N/C              J3    -34   D0440PA00X+013992Y+072413               S0      
317I2C_PSU2_SDA     J3    -33   D0440PA00X+013992Y+071413               S0      
317PSU3_DC_OK       J3    -37   D0440PA00X+013992Y+075413               S0      
317PSU3_RETURN      J3    -36   D0440PA00X+013992Y+074413               S0      
317P12V_STBY        J3    -39   D0440PA00X+013992Y+077413               S0      
317PSU3_AD0         J3    -38   D0440PA00X+013992Y+076413               S0      
317GND              J3    -42   D0440PA00X+013992Y+080413               S0      
317GND              J3    -41   D0440PA00X+013992Y+079413               S0      
317PSU3_REMOTE_P    J3    -40   D0440PA00X+013992Y+078413               S0      
317GND              J3    -44   D0440PA00X+013992Y+082413               S0      
317GND              J3    -43   D0440PA00X+013992Y+081413               S0      
317GND              J3    -47   D0440PA00X+013992Y+085413               S0      
317GND              J3    -46   D0440PA00X+013992Y+084413               S0      
317GND              J3    -45   D0440PA00X+013992Y+083413               S0      
317GND              J3    -49   D0440PA00X+013992Y+087413               S0      
317GND              J3    -48   D0440PA00X+013992Y+086413               S0      
317GND              J3    -52   D0440PA00X+013992Y+090413               S0      
317GND              J3    -51   D0440PA00X+013992Y+089413               S0      
317GND              J3    -50   D0440PA00X+013992Y+088413               S0      
317P12V             J3    -54   D0440PA00X+013992Y+092413               S0      
317P12V             J3    -53   D0440PA00X+013992Y+091413               S0      
317P12V             J3    -56   D0440PA00X+013992Y+094413               S0      
317P12V             J3    -55   D0440PA00X+013992Y+093413               S0      
317P12V             J3    -59   D0440PA00X+013992Y+097413               S0      
317P12V             J3    -58   D0440PA00X+013992Y+096413               S0      
317P12V             J3    -57   D0440PA00X+013992Y+095413               S0      
317P12V             J3    -61   D0440PA00X+013992Y+099413               S0      
317P12V             J3    -60   D0440PA00X+013992Y+098413               S0      
317P12V             J3    -64   D0440PA00X+013992Y+102413               S0      
317P12V             J3    -63   D0440PA00X+013992Y+101413               S0      
317P12V             J3    -62   D0440PA00X+013992Y+100413               S0      
317N/C              J4    -34   D0440PA00X+013992Y+107217               S0      
317I2C_PSU2_SDA     J4    -33   D0440PA00X+013992Y+106217               S0      
317PSU4_RETURN      J4    -36   D0440PA00X+013992Y+109217               S0      
317I2C_PSU2_SCL     J4    -35   D0440PA00X+013992Y+108217               S0      
317P12V_STBY        J4    -39   D0440PA00X+013992Y+112217               S0      
317PSU4_AD0         J4    -38   D0440PA00X+013992Y+111217               S0      
317PSU4_DC_OK       J4    -37   D0440PA00X+013992Y+110217               S0      
317GND              J4    -41   D0440PA00X+013992Y+114217               S0      
317PSU4_REMOTE_P    J4    -40   D0440PA00X+013992Y+113217               S0      
317GND              J4    -43   D0440PA00X+013992Y+116217               S0      
317GND              J4    -42   D0440PA00X+013992Y+115217               S0      
317GND              J4    -46   D0440PA00X+013992Y+119217               S0      
317GND              J4    -45   D0440PA00X+013992Y+118217               S0      
317GND              J4    -44   D0440PA00X+013992Y+117217               S0      
317GND              J4    -48   D0440PA00X+013992Y+121217               S0      
317GND              J4    -47   D0440PA00X+013992Y+120217               S0      
317GND              J4    -51   D0440PA00X+013992Y+124217               S0      
317GND              J4    -50   D0440PA00X+013992Y+123217               S0      
317GND              J4    -49   D0440PA00X+013992Y+122217               S0      
317P12V             J4    -53   D0440PA00X+013992Y+126217               S0      
317GND              J4    -52   D0440PA00X+013992Y+125217               S0      
317P12V             J4    -55   D0440PA00X+013992Y+128217               S0      
317P12V             J4    -54   D0440PA00X+013992Y+127217               S0      
317P12V             J4    -58   D0440PA00X+013992Y+131217               S0      
317P12V             J4    -57   D0440PA00X+013992Y+130217               S0      
317P12V             J4    -56   D0440PA00X+013992Y+129217               S0      
317P12V             J4    -60   D0440PA00X+013992Y+133217               S0      
317P12V             J4    -59   D0440PA00X+013992Y+132217               S0      
317P12V             J4    -63   D0440PA00X+013992Y+136217               S0      
317P12V             J4    -62   D0440PA00X+013992Y+135217               S0      
317P12V             J4    -61   D0440PA00X+013992Y+134217               S0      
317P12V             J4    -64   D0440PA00X+013992Y+137217               S0      
317I2C_PSU3_SDA     J5    -33   D0440PA00X+013992Y+141020               S0      
317I2C_PSU3_SCL     J5    -35   D0440PA00X+013992Y+143020               S0      
317N/C              J5    -34   D0440PA00X+013992Y+142020               S0      
317PSU5_AD0         J5    -38   D0440PA00X+013992Y+146020               S0      
317PSU5_DC_OK       J5    -37   D0440PA00X+013992Y+145020               S0      
317PSU5_RETURN      J5    -36   D0440PA00X+013992Y+144020               S0      
317PSU5_REMOTE_P    J5    -40   D0440PA00X+013992Y+148020               S0      
317P12V_STBY        J5    -39   D0440PA00X+013992Y+147020               S0      
317GND              J5    -42   D0440PA00X+013992Y+150020               S0      
317GND              J5    -41   D0440PA00X+013992Y+149020               S0      
317GND              J5    -45   D0440PA00X+013992Y+153020               S0      
317GND              J5    -44   D0440PA00X+013992Y+152020               S0      
317GND              J5    -43   D0440PA00X+013992Y+151020               S0      
317GND              J5    -47   D0440PA00X+013992Y+155020               S0      
317GND              J5    -46   D0440PA00X+013992Y+154020               S0      
317GND              J5    -50   D0440PA00X+013992Y+158020               S0      
317GND              J5    -49   D0440PA00X+013992Y+157020               S0      
317GND              J5    -48   D0440PA00X+013992Y+156020               S0      
317GND              J5    -52   D0440PA00X+013992Y+160020               S0      
317GND              J5    -51   D0440PA00X+013992Y+159020               S0      
317P12V             J5    -54   D0440PA00X+013992Y+162020               S0      
317P12V             J5    -53   D0440PA00X+013992Y+161020               S0      
317P12V             J5    -57   D0440PA00X+013992Y+165020               S0      
317P12V             J5    -56   D0440PA00X+013992Y+164020               S0      
317P12V             J5    -55   D0440PA00X+013992Y+163020               S0      
317P12V             J5    -59   D0440PA00X+013992Y+167020               S0      
317P12V             J5    -58   D0440PA00X+013992Y+166020               S0      
317P12V             J5    -62   D0440PA00X+013992Y+170020               S0      
317P12V             J5    -61   D0440PA00X+013992Y+169020               S0      
317P12V             J5    -60   D0440PA00X+013992Y+168020               S0      
317P12V             J5    -64   D0440PA00X+013992Y+172020               S0      
317P12V             J5    -63   D0440PA00X+013992Y+171020               S0      
317T11_BLAD1_TXD    VIA   -     D0100PA00X+014488Y+173886               S1      
317N/C              J6    -34   D0440PA00X+013992Y+176823               S0      
317I2C_PSU3_SDA     J6    -33   D0440PA00X+013992Y+175823               S0      
317PSU6_DC_OK       J6    -37   D0440PA00X+013992Y+179823               S0      
317PSU6_RETURN      J6    -36   D0440PA00X+013992Y+178823               S0      
317I2C_PSU3_SCL     J6    -35   D0440PA00X+013992Y+177823               S0      
317P12V_STBY        J6    -39   D0440PA00X+013992Y+181823               S0      
317PSU6_AD0         J6    -38   D0440PA00X+013992Y+180823               S0      
317GND              J6    -41   D0440PA00X+013992Y+183823               S0      
317PSU6_REMOTE_P    J6    -40   D0440PA00X+013992Y+182823               S0      
317GND              J6    -44   D0440PA00X+013992Y+186823               S0      
317GND              J6    -43   D0440PA00X+013992Y+185823               S0      
317GND              J6    -42   D0440PA00X+013992Y+184823               S0      
317GND              J6    -46   D0440PA00X+013992Y+188823               S0      
317GND              J6    -45   D0440PA00X+013992Y+187823               S0      
317GND              J6    -49   D0440PA00X+013992Y+191823               S0      
317GND              J6    -48   D0440PA00X+013992Y+190823               S0      
317GND              J6    -47   D0440PA00X+013992Y+189823               S0      
317GND              J6    -51   D0440PA00X+013992Y+193823               S0      
317GND              J6    -50   D0440PA00X+013992Y+192823               S0      
317P12V             J6    -53   D0440PA00X+013992Y+195823               S0      
317GND              J6    -52   D0440PA00X+013992Y+194823               S0      
317P12V             J6    -56   D0440PA00X+013992Y+198823               S0      
317P12V             J6    -55   D0440PA00X+013992Y+197823               S0      
317P12V             J6    -54   D0440PA00X+013992Y+196823               S0      
317P12V             J6    -58   D0440PA00X+013992Y+200823               S0      
317P12V             J6    -57   D0440PA00X+013992Y+199823               S0      
317P12V             J6    -61   D0440PA00X+013992Y+203823               S0      
317P12V             J6    -60   D0440PA00X+013992Y+202823               S0      
317P12V             J6    -59   D0440PA00X+013992Y+201823               S0      
317P12V             J6    -63   D0440PA00X+013992Y+205823               S0      
317P12V             J6    -62   D0440PA00X+013992Y+204823               S0      
317P12V             J6    -64   D0440PA00X+013992Y+206823               S0      
317N/C              J7    -H2   D0990UA00X+016339Y+002721               S0      
327GND              R9    -2          A01X+015968Y+005674X0180Y0200R180 S2      
327PSU1_RETURN      R9    -1          A01X+015653Y+005674X0180Y0200R180 S2      
317GND              VIA   -     D0100PA00X+016238Y+005674               S3      
317PSU1_RETURN      VIA   -     D0100PA00X+015756Y+005143               S1      
327GND              R12   -2          A01X+015846Y+006813X0180Y0200R180 S2      
327PSU1_AD0         R12   -1          A01X+015531Y+006813X0180Y0200R180 S2      
327P12V_STBY        R40   -2          A01X+015520Y+007250X0180Y0200     S2      
327GND              R40   -1          A01X+015835Y+007250X0180Y0200     S2      
317GND              VIA   -     D0100PA00X+016174Y+007250               S3      
317GND              VIA   -     D0100PA00X+016259Y+006813               S3      
327P12V             R1    -2          A01X+015856Y+008811X0180Y0200R180 S2      
327PSU1_REMOTE_P    R1    -1          A01X+015541Y+008811X0180Y0200R180 S2      
327NNAME10040       R86   -2          A01X+015537Y+009128X0180Y0200R270 S2      
327PSU1_REMOTE_P    R86   -1          A01X+015537Y+008813X0180Y0200R270 S2      
327NNAME10041       R110  -2          A01X+015537Y+008502X0180Y0200R090 S2      
327PSU1_REMOTE_P    R110  -1          A01X+015537Y+008817X0180Y0200R090 S2      
317P12V             VIA   -     D0100PA00X+016134Y+008811               S3      
317NNAME10040       VIA   -     D0100PA00X+015942Y+009128               S3      
317NNAME10041       VIA   -     D0100PA00X+015890Y+008502               S3      
317GND              VIA   -     D0100PA00X+016950Y+012611               S3      
317GND              VIA   -     D0100PA00X+016950Y+011863               S3      
317GND              VIA   -     D0100PA00X+016950Y+011141               S3      
317GND              VIA   -     D0100PA00X+016650Y+011141               S3      
317GND              VIA   -     D0100PA00X+016650Y+011863               S3      
317GND              VIA   -     D0100PA00X+016650Y+012611               S3      
317GND              VIA   -     D0100PA00X+016933Y+014062               S3      
317GND              VIA   -     D0100PA00X+016950Y+013271               S3      
317GND              VIA   -     D0100PA00X+016933Y+014807               S3      
317GND              VIA   -     D0100PA00X+016633Y+014807               S3      
317GND              VIA   -     D0100PA00X+016650Y+013271               S3      
317GND              VIA   -     D0100PA00X+016633Y+014062               S3      
317GND              VIA   -     D0100PA00X+016933Y+015610               S3      
317GND              VIA   -     D0100PA00X+016933Y+016362               S3      
317GND              VIA   -     D0100PA00X+016633Y+016362               S3      
317GND              VIA   -     D0100PA00X+016633Y+015610               S3      
317N/C              J8    -H2   D0990UA00X+016339Y+020221               S0      
317P12V             VIA   -     D0100PA00X+016898Y+026578               S3      
317P12V             VIA   -     D0100PA00X+016598Y+026578               S3      
317P12V             VIA   -     D0100PA00X+016898Y+029614               S3      
317P12V             VIA   -     D0100PA00X+016898Y+028680               S3      
317P12V             VIA   -     D0100PA00X+016898Y+027630               S3      
317P12V             VIA   -     D0100PA00X+016598Y+027630               S3      
317P12V             VIA   -     D0100PA00X+016598Y+028680               S3      
317P12V             VIA   -     D0100PA00X+016598Y+029614               S3      
317P12V             VIA   -     D0100PA00X+016898Y+031231               S3      
317P12V             VIA   -     D0100PA00X+016898Y+030387               S3      
317P12V             VIA   -     D0100PA00X+016598Y+030387               S3      
317P12V             VIA   -     D0100PA00X+016598Y+031231               S3      
317N/C              J9    -H2   D0990UA00X+016339Y+037721               S0      
327P12V_STBY        R4    -2          A01X+015632Y+041820X0180Y0200R270 S2      
327PSU2_AD0         R4    -1          A01X+015632Y+041505X0180Y0200R270 S2      
327GND              R11   -2          A01X+015849Y+040758X0180Y0200R180 S2      
327PSU2_RETURN      R11   -1          A01X+015534Y+040758X0180Y0200R180 S2      
327GND              R8    -2          A01X+016126Y+041820X0180Y0200R270 S2      
327PSU2_AD0         R8    -1          A01X+016126Y+041505X0180Y0200R270 S2      
317GND              VIA   -     D0100PA00X+016138Y+040758               S3      
317PSU2_RETURN      VIA   -     D0100PA00X+015687Y+040121               S1      
327P12V             R3    -2          A01X+015850Y+043612X0180Y0200R180 S2      
327PSU2_REMOTE_P    R3    -1          A01X+015535Y+043612X0180Y0200R180 S2      
327NNAME10042       R90   -2          A01X+015535Y+043927X0180Y0200R270 S2      
327PSU2_REMOTE_P    R90   -1          A01X+015535Y+043612X0180Y0200R270 S2      
327NNAME10043       R114  -2          A01X+015535Y+043297X0180Y0200R090 S2      
327PSU2_REMOTE_P    R114  -1          A01X+015535Y+043612X0180Y0200R090 S2      
317P12V             VIA   -     D0100PA00X+016152Y+043612               S3      
317GND              VIA   -     D0100PA00X+016126Y+042087               S3      
317NNAME10042       VIA   -     D0100PA00X+015902Y+043927               S3      
317NNAME10043       VIA   -     D0100PA00X+015881Y+043297               S3      
317GND              VIA   -     D0100PA00X+015943Y+046171               S3      
317GND              VIA   -     D0100PA00X+015643Y+046171               S3      
317GND              VIA   -     D0100PA00X+015943Y+048301               S3      
317GND              VIA   -     D0100PA00X+015926Y+049093               S3      
317GND              VIA   -     D0100PA00X+015943Y+046893               S3      
317GND              VIA   -     D0100PA00X+015943Y+047642               S3      
317GND              VIA   -     D0100PA00X+015643Y+047642               S3      
317GND              VIA   -     D0100PA00X+015643Y+046893               S3      
317GND              VIA   -     D0100PA00X+015626Y+049093               S3      
317GND              VIA   -     D0100PA00X+015643Y+048301               S3      
317GND              VIA   -     D0100PA00X+015926Y+051393               S3      
317GND              VIA   -     D0100PA00X+015926Y+049837               S3      
317GND              VIA   -     D0100PA00X+015926Y+050641               S3      
317GND              VIA   -     D0100PA00X+015626Y+050641               S3      
317GND              VIA   -     D0100PA00X+015626Y+049837               S3      
317GND              VIA   -     D0100PA00X+015626Y+051393               S3      
317N/C              J10   -H2   D0990UA00X+016339Y+055221               S0      
317P12V             VIA   -     D0100PA00X+015727Y+060477               S3      
317P12V             VIA   -     D0100PA00X+016027Y+060477               S3      
317P12V             VIA   -     D0100PA00X+015727Y+063342               S3      
317P12V             VIA   -     D0100PA00X+015727Y+061357               S3      
317P12V             VIA   -     D0100PA00X+015727Y+062408               S3      
317P12V             VIA   -     D0100PA00X+016027Y+062408               S3      
317P12V             VIA   -     D0100PA00X+016027Y+061357               S3      
317P12V             VIA   -     D0100PA00X+016027Y+063342               S3      
317P12V             VIA   -     D0100PA00X+015727Y+064114               S3      
317P12V             VIA   -     D0100PA00X+015727Y+064958               S3      
317P12V             VIA   -     D0100PA00X+016027Y+064958               S3      
317P12V             VIA   -     D0100PA00X+016027Y+064114               S3      
317N/C              J11   -H2   D0990UA00X+016339Y+072721               S0      
327GND              R10   -2          A01X+015895Y+075676X0180Y0200R180 S2      
327PSU3_RETURN      R10   -1          A01X+015580Y+075676X0180Y0200R180 S2      
317PSU3_RETURN      VIA   -     D0100PA00X+015661Y+075106               S1      
317GND              VIA   -     D0100PA00X+016183Y+075676               S3      
327GND              R13   -2          A01X+015867Y+076423X0180Y0200R180 S2      
327PSU3_AD0         R13   -1          A01X+015552Y+076423X0180Y0200R180 S2      
327P12V_STBY        R42   -2          A01X+015511Y+077667X0180Y0200     S2      
327GND              R42   -1          A01X+015826Y+077667X0180Y0200     S2      
327NNAME10044       R118  -2          A01X+015536Y+078098X0180Y0200R090 S2      
317GND              VIA   -     D0100PA00X+016113Y+077488               S3      
317GND              VIA   -     D0100PA00X+016164Y+076423               S3      
317NNAME10044       VIA   -     D0100PA00X+015896Y+078098               S3      
327P12V             R2    -2          A01X+015852Y+078414X0180Y0200R180 S2      
327PSU3_REMOTE_P    R2    -1          A01X+015537Y+078414X0180Y0200R180 S2      
327NNAME10035       R94   -2          A01X+015536Y+078728X0180Y0200R270 S2      
327PSU3_REMOTE_P    R94   -1          A01X+015536Y+078413X0180Y0200R270 S2      
327PSU3_REMOTE_P    R118  -1          A01X+015536Y+078413X0180Y0200R090 S2      
317P12V             VIA   -     D0100PA00X+016148Y+078414               S3      
317NNAME10035       VIA   -     D0100PA00X+015905Y+078728               S3      
317GND              VIA   -     D0100PA00X+015844Y+082273               S3      
317GND              VIA   -     D0100PA00X+016587Y+082273               S3      
317GND              VIA   -     D0100PA00X+016287Y+082273               S3      
317GND              VIA   -     D0100PA00X+015544Y+082273               S3      
317GND              VIA   -     D0100PA00X+016587Y+083021               S3      
317GND              VIA   -     D0100PA00X+015844Y+083021               S3      
317GND              VIA   -     D0100PA00X+016587Y+083680               S3      
317GND              VIA   -     D0100PA00X+015844Y+083680               S3      
317GND              VIA   -     D0100PA00X+016570Y+084472               S3      
317GND              VIA   -     D0100PA00X+015827Y+084472               S3      
317GND              VIA   -     D0100PA00X+016570Y+085217               S3      
317GND              VIA   -     D0100PA00X+015827Y+085217               S3      
317GND              VIA   -     D0100PA00X+015527Y+085217               S3      
317GND              VIA   -     D0100PA00X+016270Y+085217               S3      
317GND              VIA   -     D0100PA00X+015527Y+084472               S3      
317GND              VIA   -     D0100PA00X+016270Y+084472               S3      
317GND              VIA   -     D0100PA00X+015544Y+083680               S3      
317GND              VIA   -     D0100PA00X+016287Y+083680               S3      
317GND              VIA   -     D0100PA00X+015544Y+083021               S3      
317GND              VIA   -     D0100PA00X+016287Y+083021               S3      
317GND              VIA   -     D0100PA00X+016570Y+086020               S3      
317GND              VIA   -     D0100PA00X+015827Y+086020               S3      
317GND              VIA   -     D0100PA00X+016570Y+086772               S3      
317GND              VIA   -     D0100PA00X+015827Y+086772               S3      
317GND              VIA   -     D0100PA00X+015527Y+086772               S3      
317GND              VIA   -     D0100PA00X+016270Y+086772               S3      
317GND              VIA   -     D0100PA00X+015527Y+086020               S3      
317GND              VIA   -     D0100PA00X+016270Y+086020               S3      
317N/C              J12   -H2   D0990UA00X+016339Y+090221               S0      
317P12V             VIA   -     D0100PA00X+016370Y+097292               S3      
317P12V             VIA   -     D0100PA00X+016670Y+097292               S3      
317P12V             VIA   -     D0100PA00X+016370Y+098344               S3      
317P12V             VIA   -     D0100PA00X+016370Y+099394               S3      
317P12V             VIA   -     D0100PA00X+016670Y+099394               S3      
317P12V             VIA   -     D0100PA00X+016670Y+098344               S3      
317P12V             VIA   -     D0100PA00X+016342Y+101130               S3      
317P12V             VIA   -     D0100PA00X+016342Y+100357               S3      
317P12V             VIA   -     D0100PA00X+016342Y+101974               S3      
317P12V             VIA   -     D0100PA00X+016642Y+101974               S3      
317P12V             VIA   -     D0100PA00X+016642Y+100357               S3      
317P12V             VIA   -     D0100PA00X+016642Y+101130               S3      
317N/C              J13   -H2   D0990UA00X+016339Y+107721               S0      
327P12V_STBY        R16   -2          A01X+015612Y+111613X0180Y0200R270 S2      
327PSU4_AD0         R16   -1          A01X+015612Y+111298X0180Y0200R270 S2      
327GND              R25   -2          A01X+015928Y+110685X0180Y0200R180 S2      
327PSU4_RETURN      R25   -1          A01X+015613Y+110685X0180Y0200R180 S2      
327GND              R21   -2          A01X+016087Y+111614X0180Y0200R270 S2      
327PSU4_AD0         R21   -1          A01X+016087Y+111299X0180Y0200R270 S2      
317GND              VIA   -     D0100PA00X+016454Y+111614               S3      
317GND              VIA   -     D0100PA00X+016214Y+110685               S3      
317PSU4_RETURN      VIA   -     D0100PA00X+015685Y+110103               S1      
327P12V             R15   -2          A01X+015850Y+113218X0180Y0200R180 S2      
327PSU4_REMOTE_P    R15   -1          A01X+015535Y+113218X0180Y0200R180 S2      
327NNAME10027       R106  -2          A01X+015526Y+113534X0180Y0200R270 S2      
327PSU4_REMOTE_P    R106  -1          A01X+015526Y+113219X0180Y0200R270 S2      
327NNAME10045       R122  -2          A01X+015526Y+112905X0180Y0200R090 S2      
327PSU4_REMOTE_P    R122  -1          A01X+015526Y+113220X0180Y0200R090 S2      
317NNAME10027       VIA   -     D0100PA00X+015938Y+113615               S3      
317NNAME10045       VIA   -     D0100PA00X+015846Y+112905               S3      
317GND              VIA   -     D0100PA00X+015612Y+117626               S3      
317GND              VIA   -     D0100PA00X+016355Y+117626               S3      
317GND              VIA   -     D0100PA00X+016355Y+118374               S3      
317GND              VIA   -     D0100PA00X+016355Y+119034               S3      
317GND              VIA   -     D0100PA00X+015612Y+119034               S3      
317GND              VIA   -     D0100PA00X+015612Y+118374               S3      
317GND              VIA   -     D0100PA00X+016355Y+116904               S3      
317GND              VIA   -     D0100PA00X+015612Y+116904               S3      
317GND              VIA   -     D0100PA00X+015312Y+116904               S3      
317GND              VIA   -     D0100PA00X+016055Y+116904               S3      
317GND              VIA   -     D0100PA00X+015312Y+118374               S3      
317GND              VIA   -     D0100PA00X+015312Y+119034               S3      
317GND              VIA   -     D0100PA00X+016055Y+119034               S3      
317GND              VIA   -     D0100PA00X+016055Y+118374               S3      
317GND              VIA   -     D0100PA00X+016055Y+117626               S3      
317GND              VIA   -     D0100PA00X+015312Y+117626               S3      
317GND              VIA   -     D0100PA00X+016938Y+118374               S3      
317GND              VIA   -     D0100PA00X+016938Y+119034               S3      
317GND              VIA   -     D0100PA00X+016938Y+117626               S3      
317GND              VIA   -     D0100PA00X+016338Y+119825               S3      
317GND              VIA   -     D0100PA00X+015595Y+119825               S3      
317GND              VIA   -     D0100PA00X+015295Y+119825               S3      
317GND              VIA   -     D0100PA00X+016038Y+119825               S3      
317GND              VIA   -     D0100PA00X+016920Y+119825               S3      
317N/C              J14   -H2   D0990UA00X+016339Y+125221               S0      
317P12V             VIA   -     D0100PA00X+015875Y+130773               S3      
317P12V             VIA   -     D0100PA00X+015575Y+130773               S3      
317P12V             VIA   -     D0100PA00X+015875Y+132875               S3      
317P12V             VIA   -     D0100PA00X+015875Y+131825               S3      
317P12V             VIA   -     D0100PA00X+015575Y+131825               S3      
317P12V             VIA   -     D0100PA00X+015575Y+132875               S3      
317P12V             VIA   -     D0100PA00X+015875Y+135426               S3      
317P12V             VIA   -     D0100PA00X+015875Y+133809               S3      
317P12V             VIA   -     D0100PA00X+015875Y+134582               S3      
317P12V             VIA   -     D0100PA00X+015575Y+134582               S3      
317P12V             VIA   -     D0100PA00X+015575Y+133809               S3      
317P12V             VIA   -     D0100PA00X+015575Y+135426               S3      
317T9_BLAD2_RXD     VIA   -     D0100PA00X+015862Y+139945               S1      
317T9_BLAD2_TXD     VIA   -     D0100PA00X+016404Y+140023               S1      
317T9_BLAD3_TXD     VIA   -     D0100PA00X+017035Y+140132               S1      
317N/C              J15   -H2   D0990UA00X+016339Y+142721               S0      
327GND              R24   -2          A01X+016025Y+145708X0180Y0200R180 S2      
327PSU5_RETURN      R24   -1          A01X+015710Y+145708X0180Y0200R180 S2      
317PSU5_RETURN      VIA   -     D0100PA00X+015919Y+145111               S1      
317GND              VIA   -     D0100PA00X+016310Y+145708               S3      
327P12V             R14   -2          A01X+015898Y+148027X0180Y0200R180 S2      
327PSU5_REMOTE_P    R14   -1          A01X+015583Y+148027X0180Y0200R180 S2      
327GND              R27   -2          A01X+015951Y+146265X0180Y0200R180 S2      
327PSU5_AD0         R27   -1          A01X+015636Y+146265X0180Y0200R180 S2      
327P12V_STBY        R44   -2          A01X+015565Y+147302X0180Y0200     S2      
327GND              R44   -1          A01X+015880Y+147302X0180Y0200     S2      
327PSU5_REMOTE_P    R102  -1          A01X+015583Y+148027X0180Y0200R270 S2      
327NNAME10046       R126  -2          A01X+015582Y+147712X0180Y0200R090 S2      
327PSU5_REMOTE_P    R126  -1          A01X+015582Y+148027X0180Y0200R090 S2      
317GND              VIA   -     D0100PA00X+016252Y+146265               S3      
317GND              VIA   -     D0100PA00X+016224Y+147138               S3      
317NNAME10046       VIA   -     D0100PA00X+015922Y+147712               S3      
327NNAME10047       R102  -2          A01X+015583Y+148342X0180Y0200R270 S2      
317GND              VIA   -     D0100PA00X+015411Y+149922               S3      
317GND              VIA   -     D0100PA00X+016154Y+149922               S3      
317GND              VIA   -     D0100PA00X+016154Y+150644               S3      
317GND              VIA   -     D0100PA00X+017036Y+150644               S3      
317GND              VIA   -     D0100PA00X+015411Y+150644               S3      
317GND              VIA   -     D0100PA00X+015711Y+150644               S3      
317GND              VIA   -     D0100PA00X+016454Y+150644               S3      
317GND              VIA   -     D0100PA00X+016454Y+149922               S3      
317GND              VIA   -     D0100PA00X+015711Y+149922               S3      
317NNAME10047       VIA   -     D0100PA00X+015953Y+148343               S3      
317GND              VIA   -     D0100PA00X+015394Y+152844               S3      
317GND              VIA   -     D0100PA00X+015411Y+151392               S3      
317GND              VIA   -     D0100PA00X+015411Y+152052               S3      
317GND              VIA   -     D0100PA00X+017036Y+151392               S3      
317GND              VIA   -     D0100PA00X+017036Y+152052               S3      
317GND              VIA   -     D0100PA00X+016154Y+152052               S3      
317GND              VIA   -     D0100PA00X+016154Y+151392               S3      
317GND              VIA   -     D0100PA00X+016137Y+152844               S3      
317GND              VIA   -     D0100PA00X+017019Y+152844               S3      
317GND              VIA   -     D0100PA00X+016437Y+152844               S3      
317GND              VIA   -     D0100PA00X+016454Y+151392               S3      
317GND              VIA   -     D0100PA00X+016454Y+152052               S3      
317GND              VIA   -     D0100PA00X+015711Y+152052               S3      
317GND              VIA   -     D0100PA00X+015711Y+151392               S3      
317GND              VIA   -     D0100PA00X+015694Y+152844               S3      
317GND              VIA   -     D0100PA00X+015394Y+153588               S3      
317GND              VIA   -     D0100PA00X+015394Y+154392               S3      
317GND              VIA   -     D0100PA00X+015394Y+155144               S3      
317GND              VIA   -     D0100PA00X+017019Y+153588               S3      
317GND              VIA   -     D0100PA00X+017019Y+154392               S3      
317GND              VIA   -     D0100PA00X+016137Y+153588               S3      
317GND              VIA   -     D0100PA00X+016137Y+154392               S3      
317GND              VIA   -     D0100PA00X+016137Y+155144               S3      
317GND              VIA   -     D0100PA00X+017019Y+155144               S3      
317GND              VIA   -     D0100PA00X+016437Y+155144               S3      
317GND              VIA   -     D0100PA00X+016437Y+154392               S3      
317GND              VIA   -     D0100PA00X+016437Y+153588               S3      
317GND              VIA   -     D0100PA00X+015694Y+155144               S3      
317GND              VIA   -     D0100PA00X+015694Y+154392               S3      
317GND              VIA   -     D0100PA00X+015694Y+153588               S3      
317N/C              J16   -H2   D0990UA00X+016339Y+160221               S0      
317P12V             VIA   -     D0100PA00X+016149Y+166776               S3      
317P12V             VIA   -     D0100PA00X+016149Y+165725               S3      
317P12V             VIA   -     D0100PA00X+015849Y+165725               S3      
317P12V             VIA   -     D0100PA00X+015849Y+166776               S3      
317P12V             VIA   -     D0100PA00X+016149Y+169533               S3      
317P12V             VIA   -     D0100PA00X+016149Y+168761               S3      
317P12V             VIA   -     D0100PA00X+016149Y+167827               S3      
317P12V             VIA   -     D0100PA00X+015849Y+167827               S3      
317P12V             VIA   -     D0100PA00X+015849Y+168761               S3      
317P12V             VIA   -     D0100PA00X+015849Y+169533               S3      
317P12V             VIA   -     D0100PA00X+016149Y+170377               S3      
317P12V             VIA   -     D0100PA00X+015849Y+170377               S3      
317T11_BLAD1_RXD    VIA   -     D0100PA00X+016326Y+173762               S1      
317T11_BLAD3_TXD    VIA   -     D0100PA00X+015031Y+173701               S1      
317T11_BLAD2_RXD    VIA   -     D0100PA00X+016815Y+173921               S1      
317T11_BLAD4_RXD    VIA   -     D0100PA00X+016578Y+173290               S1      
317T11_BLAD3_RXD    VIA   -     D0100PA00X+015618Y+173524               S1      
317N/C              J17   -H2   D0990UA00X+016339Y+177721               S0      
327GND              R26   -2          A01X+015884Y+180774X0180Y0200R180 S2      
327PSU6_RETURN      R26   -1          A01X+015569Y+180774X0180Y0200R180 S2      
327GND              R23   -2          A01X+015856Y+181563X0180Y0200R180 S2      
327PSU6_AD0         R23   -1          A01X+015541Y+181563X0180Y0200R180 S2      
317GND              VIA   -     D0100PA00X+016325Y+181563               S3      
317GND              VIA   -     D0100PA00X+016214Y+180774               S3      
317PSU6_RETURN      VIA   -     D0100PA00X+015645Y+180082               S1      
327P12V             R17   -2          A01X+015881Y+182823X0180Y0200R180 S2      
327PSU6_REMOTE_P    R17   -1          A01X+015566Y+182823X0180Y0200R180 S2      
327P12V_STBY        R18   -2          A01X+015541Y+182036X0180Y0200     S2      
327PSU6_AD0         R18   -1          A01X+015856Y+182036X0180Y0200     S2      
327NNAME10025       R98   -2          A01X+015557Y+183138X0180Y0200R270 S2      
327PSU6_REMOTE_P    R98   -1          A01X+015557Y+182823X0180Y0200R270 S2      
327NNAME10048       R130  -2          A01X+015556Y+182509X0180Y0200R090 S2      
327PSU6_REMOTE_P    R130  -1          A01X+015556Y+182824X0180Y0200R090 S2      
317P12V             VIA   -     D0100PA00X+016184Y+182823               S3      
317NNAME10025       VIA   -     D0100PA00X+015982Y+183138               S3      
317NNAME10048       VIA   -     D0100PA00X+015908Y+182509               S3      
317GND              VIA   -     D0100PA00X+015509Y+186600               S3      
317GND              VIA   -     D0100PA00X+016252Y+186600               S3      
317GND              VIA   -     D0100PA00X+015952Y+186600               S3      
317GND              VIA   -     D0100PA00X+015209Y+186600               S3      
317GND              VIA   -     D0100PA00X+015509Y+188071               S3      
317GND              VIA   -     D0100PA00X+015509Y+188730               S3      
317GND              VIA   -     D0100PA00X+016252Y+188730               S3      
317GND              VIA   -     D0100PA00X+016252Y+188071               S3      
317GND              VIA   -     D0100PA00X+016252Y+187322               S3      
317GND              VIA   -     D0100PA00X+015509Y+187322               S3      
317GND              VIA   -     D0100PA00X+015209Y+187322               S3      
317GND              VIA   -     D0100PA00X+016834Y+187322               S3      
317GND              VIA   -     D0100PA00X+015952Y+187322               S3      
317GND              VIA   -     D0100PA00X+015952Y+188071               S3      
317GND              VIA   -     D0100PA00X+015952Y+188730               S3      
317GND              VIA   -     D0100PA00X+016834Y+188730               S3      
317GND              VIA   -     D0100PA00X+016834Y+188071               S3      
317GND              VIA   -     D0100PA00X+015209Y+188730               S3      
317GND              VIA   -     D0100PA00X+015209Y+188071               S3      
317GND              VIA   -     D0100PA00X+015492Y+190266               S3      
317GND              VIA   -     D0100PA00X+015492Y+191070               S3      
317GND              VIA   -     D0100PA00X+016235Y+190266               S3      
317GND              VIA   -     D0100PA00X+016235Y+191070               S3      
317GND              VIA   -     D0100PA00X+015492Y+189522               S3      
317GND              VIA   -     D0100PA00X+016235Y+189522               S3      
317GND              VIA   -     D0100PA00X+016817Y+189522               S3      
317GND              VIA   -     D0100PA00X+015935Y+189522               S3      
317GND              VIA   -     D0100PA00X+015192Y+189522               S3      
317GND              VIA   -     D0100PA00X+015935Y+191070               S3      
317GND              VIA   -     D0100PA00X+015935Y+190266               S3      
317GND              VIA   -     D0100PA00X+016817Y+191070               S3      
317GND              VIA   -     D0100PA00X+016817Y+190266               S3      
317GND              VIA   -     D0100PA00X+015192Y+191070               S3      
317GND              VIA   -     D0100PA00X+015192Y+190266               S3      
317GND              VIA   -     D0100PA00X+015492Y+191822               S3      
317GND              VIA   -     D0100PA00X+016235Y+191822               S3      
317GND              VIA   -     D0100PA00X+016817Y+191822               S3      
317GND              VIA   -     D0100PA00X+015935Y+191822               S3      
317GND              VIA   -     D0100PA00X+015192Y+191822               S3      
317N/C              J18   -H2   D0990UA00X+016339Y+195221               S0      
317GND              VIA   -     D0100PA00X+015999Y+208361               S3      
317GND              VIA   -     D0100PA00X+017522Y+000300               S3      
317GND              J7    -P1   D0300PA00X+017339Y+003252               S0      
317GND              J7    -P32  D0300PA00X+017339Y+002189               S0      
317GND              J7    -P2   D0300PA00X+018339Y+003252               S0      
317GND              J7    -P31  D0300PA00X+018339Y+002189               S0      
317GND              J7    -P3   D0300PA00X+019339Y+003252               S0      
317GND              J7    -P30  D0300PA00X+019339Y+002189               S0      
317GND              CE1   -2    D0360PA00X+018976Y+007311               S0      
317GND              VIA   -     D0100PA00X+017693Y+012611               S3      
317GND              VIA   -     D0100PA00X+017693Y+011863               S3      
317GND              VIA   -     D0100PA00X+017693Y+011141               S3      
317GND              VIA   -     D0100PA00X+017393Y+011141               S3      
317GND              VIA   -     D0100PA00X+017393Y+011863               S3      
317GND              VIA   -     D0100PA00X+017393Y+012611               S3      
317GND              CE2   -2    D0360PA00X+019029Y+015205               S0      
317GND              VIA   -     D0100PA00X+017676Y+014062               S3      
317GND              VIA   -     D0100PA00X+017693Y+013271               S3      
317GND              VIA   -     D0100PA00X+017676Y+014807               S3      
317GND              VIA   -     D0100PA00X+017376Y+014807               S3      
317GND              VIA   -     D0100PA00X+017393Y+013271               S3      
317GND              VIA   -     D0100PA00X+017376Y+014062               S3      
317GND              VIA   -     D0100PA00X+017676Y+015610               S3      
317GND              VIA   -     D0100PA00X+017676Y+016362               S3      
317GND              VIA   -     D0100PA00X+017376Y+016362               S3      
317GND              VIA   -     D0100PA00X+017376Y+015610               S3      
317GND              J8    -P32  D0300PA00X+017339Y+019689               S0      
317GND              J8    -P31  D0300PA00X+018339Y+019689               S0      
317GND              J8    -P30  D0300PA00X+019339Y+019689               S0      
317GND              J8    -P1   D0300PA00X+017339Y+020752               S0      
317GND              J8    -P2   D0300PA00X+018339Y+020752               S0      
317GND              J8    -P3   D0300PA00X+019339Y+020752               S0      
317GND              CE3   -2    D0360PA00X+019036Y+024757               S0      
317GND              VIA   -     D0100PA00X+017503Y+026159               S3      
317GND              VIA   -     D0100PA00X+017503Y+026881               S3      
317GND              VIA   -     D0100PA00X+017803Y+026881               S3      
317GND              VIA   -     D0100PA00X+017803Y+026159               S3      
317GND              VIA   -     D0100PA00X+017503Y+028289               S3      
317GND              VIA   -     D0100PA00X+017486Y+029081               S3      
317GND              VIA   -     D0100PA00X+017486Y+029825               S3      
317GND              VIA   -     D0100PA00X+017503Y+027630               S3      
317GND              VIA   -     D0100PA00X+017803Y+027630               S3      
317GND              VIA   -     D0100PA00X+017786Y+029825               S3      
317GND              VIA   -     D0100PA00X+017786Y+029081               S3      
317GND              VIA   -     D0100PA00X+017803Y+028289               S3      
317GND              VIA   -     D0100PA00X+017486Y+031381               S3      
317GND              VIA   -     D0100PA00X+017486Y+030629               S3      
317GND              VIA   -     D0100PA00X+017786Y+030629               S3      
317GND              VIA   -     D0100PA00X+017786Y+031381               S3      
317GND              CE4   -2    D0360PA00X+019082Y+033179               S0      
317GND              J9    -P32  D0300PA00X+017339Y+037189               S0      
317GND              J9    -P31  D0300PA00X+018339Y+037189               S0      
317GND              J9    -P30  D0300PA00X+019339Y+037189               S0      
317GND              J9    -P1   D0300PA00X+017339Y+038252               S0      
317GND              J9    -P2   D0300PA00X+018339Y+038252               S0      
317GND              J9    -P3   D0300PA00X+019339Y+038252               S0      
317GND              CE5   -2    D0360PA00X+018976Y+042173               S0      
317GND              CE6   -2    D0360PA00X+019055Y+050652               S0      
317GND              J10   -P1   D0300PA00X+017339Y+055752               S0      
317GND              J10   -P32  D0300PA00X+017339Y+054689               S0      
317GND              J10   -P2   D0300PA00X+018339Y+055752               S0      
317GND              J10   -P31  D0300PA00X+018339Y+054689               S0      
317GND              J10   -P3   D0300PA00X+019339Y+055752               S0      
317GND              J10   -P30  D0300PA00X+019339Y+054689               S0      
317GND              CE8   -2    D0360PA00X+019289Y+059813               S0      
317GND              CE9   -2    D0360PA00X+019082Y+068165               S0      
317GND              J11   -P1   D0300PA00X+017339Y+073252               S0      
317GND              J11   -P32  D0300PA00X+017339Y+072189               S0      
317GND              J11   -P2   D0300PA00X+018339Y+073252               S0      
317GND              J11   -P31  D0300PA00X+018339Y+072189               S0      
317GND              J11   -P3   D0300PA00X+019339Y+073252               S0      
317GND              J11   -P30  D0300PA00X+019339Y+072189               S0      
317GND              CE10  -2    D0360PA00X+019185Y+077453               S0      
317GND              VIA   -     D0100PA00X+018219Y+082273               S3      
317GND              VIA   -     D0100PA00X+017470Y+082273               S3      
317GND              VIA   -     D0100PA00X+017170Y+082273               S3      
317GND              VIA   -     D0100PA00X+017919Y+082273               S3      
317GND              VIA   -     D0100PA00X+017452Y+084472               S3      
317GND              VIA   -     D0100PA00X+017452Y+085217               S3      
317GND              VIA   -     D0100PA00X+018219Y+083021               S3      
317GND              VIA   -     D0100PA00X+017470Y+083021               S3      
317GND              VIA   -     D0100PA00X+018219Y+083680               S3      
317GND              VIA   -     D0100PA00X+017470Y+083680               S3      
317GND              VIA   -     D0100PA00X+018202Y+084472               S3      
317GND              VIA   -     D0100PA00X+018202Y+085217               S3      
317GND              VIA   -     D0100PA00X+017902Y+085217               S3      
317GND              VIA   -     D0100PA00X+017902Y+084472               S3      
317GND              VIA   -     D0100PA00X+017170Y+083680               S3      
317GND              VIA   -     D0100PA00X+017919Y+083680               S3      
317GND              VIA   -     D0100PA00X+017170Y+083021               S3      
317GND              VIA   -     D0100PA00X+017919Y+083021               S3      
317GND              VIA   -     D0100PA00X+017152Y+085217               S3      
317GND              VIA   -     D0100PA00X+017152Y+084472               S3      
317GND              CE11  -2    D0360PA00X+019161Y+085624               S0      
317GND              VIA   -     D0100PA00X+017452Y+086020               S3      
317GND              VIA   -     D0100PA00X+017452Y+086772               S3      
317GND              VIA   -     D0100PA00X+018202Y+086020               S3      
317GND              VIA   -     D0100PA00X+018202Y+086772               S3      
317GND              VIA   -     D0100PA00X+017902Y+086772               S3      
317GND              VIA   -     D0100PA00X+017902Y+086020               S3      
317GND              VIA   -     D0100PA00X+017152Y+086772               S3      
317GND              VIA   -     D0100PA00X+017152Y+086020               S3      
317GND              J12   -P32  D0300PA00X+017339Y+089689               S0      
317GND              J12   -P31  D0300PA00X+018339Y+089689               S0      
317GND              J12   -P30  D0300PA00X+019339Y+089689               S0      
317GND              J12   -P1   D0300PA00X+017339Y+090752               S0      
317GND              J12   -P2   D0300PA00X+018339Y+090752               S0      
317GND              J12   -P3   D0300PA00X+019339Y+090752               S0      
317GND              CE12  -2    D0360PA00X+019631Y+094720               S0      
327P12V             R88   -2          A01X+018437Y+093798X0180Y0200R180 S2      
327NNAME10040       R88   -1          A01X+018122Y+093798X0180Y0200R180 S2      
327GND              R89   -2          A01X+018428Y+094358X0180Y0200R180 S2      
327NNAME10030       R89   -1          A01X+018113Y+094358X0180Y0200R180 S2      
317GND              VIA   -     D0100PA00X+018428Y+094833               S3      
317NNAME10030       VIA   -     D0100PA00X+017599Y+094454               S1      
317NNAME10040       VIA   -     D0100PA00X+017601Y+093683               S1      
327GND              R91   -2          A01X+018420Y+096267X0180Y0200R180 S2      
327NNAME10031       R91   -1          A01X+018105Y+096267X0180Y0200R180 S2      
327P12V             R92   -2          A01X+018429Y+095707X0180Y0200R180 S2      
327NNAME10042       R92   -1          A01X+018114Y+095707X0180Y0200R180 S2      
327P12V             R96   -2          A01X+018454Y+097355X0180Y0200R180 S2      
327NNAME10035       R96   -1          A01X+018139Y+097355X0180Y0200R180 S2      
317GND              VIA   -     D0100PA00X+018420Y+096737               S3      
317NNAME10031       VIA   -     D0100PA00X+017536Y+096349               S1      
317NNAME10042       VIA   -     D0100PA00X+017556Y+095596               S1      
317NNAME10035       VIA   -     D0100PA00X+017514Y+097249               S1      
327P12V             R100  -2          A01X+018440Y+099096X0180Y0200R180 S2      
327NNAME10025       R100  -1          A01X+018125Y+099096X0180Y0200R180 S2      
327GND              R95   -2          A01X+018463Y+097915X0180Y0200R180 S2      
327NNAME10033       R95   -1          A01X+018148Y+097915X0180Y0200R180 S2      
327GND              R99   -2          A01X+018435Y+099656X0180Y0200R180 S2      
327NNAME10026       R99   -1          A01X+018120Y+099656X0180Y0200R180 S2      
317GND              VIA   -     D0100PA00X+018463Y+098342               S3      
317NNAME10033       VIA   -     D0100PA00X+017502Y+098028               S1      
317NNAME10025       VIA   -     D0100PA00X+017574Y+098996               S1      
317NNAME10026       VIA   -     D0100PA00X+017545Y+099766               S1      
327GND              R107  -2          A01X+018412Y+101531X0180Y0200R180 S2      
327NNAME10028       R107  -1          A01X+018097Y+101531X0180Y0200R180 S2      
327P12V             R108  -2          A01X+018412Y+100971X0180Y0200R180 S2      
327NNAME10027       R108  -1          A01X+018097Y+100971X0180Y0200R180 S2      
317GND              VIA   -     D0100PA00X+018435Y+100156               S3      
317GND              VIA   -     D0100PA00X+018412Y+101928               S3      
317GND              VIA   -     D0100PA00X+018839Y+102081               S3      
317NNAME10027       VIA   -     D0100PA00X+017570Y+100873               S1      
317NNAME10028       VIA   -     D0100PA00X+017547Y+101630               S1      
317GND              CE7   -2    D0360PA00X+019552Y+103254               S0      
327GND              R103  -2          A01X+018233Y+102502X0180Y0200R180 S2      
327NNAME10037       R103  -1          A01X+017918Y+102502X0180Y0200R180 S2      
327P12V             R104  -2          A01X+018233Y+103062X0180Y0200R180 S2      
327NNAME10047       R104  -1          A01X+017918Y+103062X0180Y0200R180 S2      
317NNAME10047       VIA   -     D0100PA00X+017545Y+103177               S1      
317NNAME10037       VIA   -     D0100PA00X+017590Y+102400               S1      
317GND              J13   -P32  D0300PA00X+017339Y+107189               S0      
317GND              J13   -P31  D0300PA00X+018339Y+107189               S0      
317GND              J13   -P30  D0300PA00X+019339Y+107189               S0      
317GND              J13   -P1   D0300PA00X+017339Y+108252               S0      
317GND              J13   -P2   D0300PA00X+018339Y+108252               S0      
317GND              J13   -P3   D0300PA00X+019339Y+108252               S0      
317GND              CE13  -2    D0360PA00X+019125Y+112286               S0      
317GND              VIA   -     D0100PA00X+017987Y+117626               S3      
317GND              VIA   -     D0100PA00X+017987Y+119034               S3      
317GND              VIA   -     D0100PA00X+017987Y+118374               S3      
317GND              VIA   -     D0100PA00X+017238Y+117626               S3      
317GND              VIA   -     D0100PA00X+017238Y+119034               S3      
317GND              VIA   -     D0100PA00X+017238Y+118374               S3      
317GND              VIA   -     D0100PA00X+017687Y+118374               S3      
317GND              VIA   -     D0100PA00X+017687Y+119034               S3      
317GND              VIA   -     D0100PA00X+017687Y+117626               S3      
317GND              CE14  -2    D0360PA00X+019134Y+120623               S0      
317GND              VIA   -     D0100PA00X+017970Y+119825               S3      
317GND              VIA   -     D0100PA00X+017220Y+119825               S3      
317GND              VIA   -     D0100PA00X+017670Y+119825               S3      
317GND              J14   -P1   D0300PA00X+017339Y+125752               S0      
317GND              J14   -P32  D0300PA00X+017339Y+124689               S0      
317GND              J14   -P2   D0300PA00X+018339Y+125752               S0      
317GND              J14   -P31  D0300PA00X+018339Y+124689               S0      
317GND              J14   -P3   D0300PA00X+019339Y+125752               S0      
317GND              J14   -P30  D0300PA00X+019339Y+124689               S0      
317GND              CE15  -2    D0360PA00X+019185Y+129910               S0      
317GND              CE16  -2    D0360PA00X+019055Y+138097               S0      
317T9_BLAD3_RXD     VIA   -     D0100PA00X+017608Y+140232               S1      
317GND              J15   -P1   D0300PA00X+017339Y+143252               S0      
317GND              J15   -P32  D0300PA00X+017339Y+142189               S0      
317GND              J15   -P2   D0300PA00X+018339Y+143252               S0      
317GND              J15   -P31  D0300PA00X+018339Y+142189               S0      
317GND              J15   -P3   D0300PA00X+019339Y+143252               S0      
317GND              J15   -P30  D0300PA00X+019339Y+142189               S0      
317GND              CE17  -2    D0360PA00X+018946Y+147416               S0      
317GND              VIA   -     D0100PA00X+017786Y+150644               S3      
317GND              VIA   -     D0100PA00X+017336Y+150644               S3      
317GND              VIA   -     D0100PA00X+018086Y+150644               S3      
317GND              VIA   -     D0100PA00X+017786Y+151392               S3      
317GND              VIA   -     D0100PA00X+017786Y+152052               S3      
317GND              VIA   -     D0100PA00X+017769Y+152844               S3      
317GND              VIA   -     D0100PA00X+017319Y+152844               S3      
317GND              VIA   -     D0100PA00X+017336Y+152052               S3      
317GND              VIA   -     D0100PA00X+017336Y+151392               S3      
317GND              VIA   -     D0100PA00X+018069Y+152844               S3      
317GND              VIA   -     D0100PA00X+018086Y+152052               S3      
317GND              VIA   -     D0100PA00X+018086Y+151392               S3      
317GND              VIA   -     D0100PA00X+017769Y+153588               S3      
317GND              VIA   -     D0100PA00X+017769Y+154392               S3      
317GND              VIA   -     D0100PA00X+017769Y+155144               S3      
317GND              VIA   -     D0100PA00X+017319Y+155144               S3      
317GND              VIA   -     D0100PA00X+017319Y+154392               S3      
317GND              VIA   -     D0100PA00X+017319Y+153588               S3      
317GND              VIA   -     D0100PA00X+018069Y+155144               S3      
317GND              VIA   -     D0100PA00X+018069Y+154392               S3      
317GND              VIA   -     D0100PA00X+018069Y+153588               S3      
317GND              CE18  -2    D0360PA00X+019108Y+155728               S0      
317GND              J16   -P32  D0300PA00X+017339Y+159689               S0      
317GND              J16   -P31  D0300PA00X+018339Y+159689               S0      
317GND              J16   -P30  D0300PA00X+019339Y+159689               S0      
317GND              J16   -P1   D0300PA00X+017339Y+160752               S0      
317GND              J16   -P2   D0300PA00X+018339Y+160752               S0      
317GND              J16   -P3   D0300PA00X+019339Y+160752               S0      
317GND              CE19  -2    D0360PA00X+019214Y+164818               S0      
317GND              CE20  -2    D0360PA00X+019161Y+173135               S0      
317T11_BLAD4_TXD    VIA   -     D0100PA00X+017339Y+173605               S1      
317GND              J17   -P32  D0300PA00X+017339Y+177189               S0      
317GND              J17   -P31  D0300PA00X+018339Y+177189               S0      
317GND              J17   -P30  D0300PA00X+019339Y+177189               S0      
317GND              J17   -P1   D0300PA00X+017339Y+178252               S0      
317GND              J17   -P2   D0300PA00X+018339Y+178252               S0      
317GND              J17   -P3   D0300PA00X+019339Y+178252               S0      
317GND              CE22  -2    D0360PA00X+019153Y+182323               S0      
317GND              VIA   -     D0100PA00X+017884Y+188071               S3      
317GND              VIA   -     D0100PA00X+017884Y+188730               S3      
317GND              VIA   -     D0100PA00X+017884Y+187322               S3      
317GND              VIA   -     D0100PA00X+017134Y+188071               S3      
317GND              VIA   -     D0100PA00X+017134Y+188730               S3      
317GND              VIA   -     D0100PA00X+017134Y+187322               S3      
317GND              VIA   -     D0100PA00X+017584Y+187322               S3      
317GND              VIA   -     D0100PA00X+017584Y+188730               S3      
317GND              VIA   -     D0100PA00X+017584Y+188071               S3      
317GND              CE21  -2    D0360PA00X+019029Y+190042               S0      
317GND              VIA   -     D0100PA00X+017867Y+190266               S3      
317GND              VIA   -     D0100PA00X+017867Y+191070               S3      
317GND              VIA   -     D0100PA00X+017867Y+189522               S3      
317GND              VIA   -     D0100PA00X+017117Y+190266               S3      
317GND              VIA   -     D0100PA00X+017117Y+191070               S3      
317GND              VIA   -     D0100PA00X+017117Y+189522               S3      
317GND              VIA   -     D0100PA00X+017567Y+189522               S3      
317GND              VIA   -     D0100PA00X+017567Y+191070               S3      
317GND              VIA   -     D0100PA00X+017567Y+190266               S3      
317GND              VIA   -     D0100PA00X+017867Y+191822               S3      
317GND              VIA   -     D0100PA00X+017117Y+191822               S3      
317GND              VIA   -     D0100PA00X+017567Y+191822               S3      
317GND              J18   -P1   D0300PA00X+017339Y+195752               S0      
317GND              J18   -P32  D0300PA00X+017339Y+194689               S0      
317GND              J18   -P2   D0300PA00X+018339Y+195752               S0      
317GND              J18   -P31  D0300PA00X+018339Y+194689               S0      
317GND              J18   -P3   D0300PA00X+019339Y+195752               S0      
317GND              J18   -P30  D0300PA00X+019339Y+194689               S0      
317GND              CE23  -2    D0360PA00X+019213Y+199873               S0      
317GND              CE24  -2    D0360PA00X+019153Y+204339               S0      
317GND              J7    -P4   D0300PA00X+020339Y+003252               S0      
317GND              J7    -P29  D0300PA00X+020339Y+002189               S0      
317GND              J7    -P5   D0300PA00X+021339Y+003252               S0      
317GND              J7    -P28  D0300PA00X+021339Y+002189               S0      
317P12V             CE1   -1    D0360PA00X+020354Y+007311               S0      
317P12V             CE2   -1    D0360PA00X+020407Y+015205               S0      
317P12V             VIA   -     D0100PA00X+021773Y+015396               S3      
317P12V             VIA   -     D0100PA00X+021773Y+017013               S3      
317P12V             VIA   -     D0100PA00X+021773Y+016169               S3      
317P12V             VIA   -     D0100PA00X+021773Y+016469               S3      
317P12V             VIA   -     D0100PA00X+021773Y+017313               S3      
317P12V             VIA   -     D0100PA00X+021773Y+015696               S3      
317GND              J8    -P29  D0300PA00X+020339Y+019689               S0      
317GND              J8    -P28  D0300PA00X+021339Y+019689               S0      
317GND              J8    -P4   D0300PA00X+020339Y+020752               S0      
317GND              J8    -P5   D0300PA00X+021339Y+020752               S0      
317P12V             CE3   -1    D0360PA00X+020414Y+024757               S0      
317P12V             CE4   -1    D0360PA00X+020460Y+033179               S0      
317GND              J9    -P29  D0300PA00X+020339Y+037189               S0      
317GND              J9    -P28  D0300PA00X+021339Y+037189               S0      
317GND              J9    -P4   D0300PA00X+020339Y+038252               S0      
317GND              J9    -P5   D0300PA00X+021339Y+038252               S0      
317P12V             CE5   -1    D0360PA00X+020354Y+042173               S0      
317P12V             CE6   -1    D0360PA00X+020433Y+050652               S0      
317GND              J10   -P4   D0300PA00X+020339Y+055752               S0      
317GND              J10   -P29  D0300PA00X+020339Y+054689               S0      
317GND              J10   -P5   D0300PA00X+021339Y+055752               S0      
317GND              J10   -P28  D0300PA00X+021339Y+054689               S0      
317P12V             CE8   -1    D0360PA00X+020667Y+059813               S0      
317P12V             CE9   -1    D0360PA00X+020460Y+068165               S0      
317GND              J11   -P4   D0300PA00X+020339Y+073252               S0      
317GND              J11   -P29  D0300PA00X+020339Y+072189               S0      
317GND              J11   -P5   D0300PA00X+021339Y+073252               S0      
317GND              J11   -P28  D0300PA00X+021339Y+072189               S0      
317P12V             CE10  -1    D0360PA00X+020563Y+077453               S0      
317P12V             CE11  -1    D0360PA00X+020539Y+085624               S0      
317GND              J12   -P29  D0300PA00X+020339Y+089689               S0      
317GND              J12   -P28  D0300PA00X+021339Y+089689               S0      
317GND              J12   -P4   D0300PA00X+020339Y+090752               S0      
317GND              J12   -P5   D0300PA00X+021339Y+090752               S0      
317P12V             CE12  -1    D0360PA00X+021009Y+094720               S0      
317P12V             CE7   -1    D0360PA00X+020930Y+103254               S0      
317GND              J13   -P29  D0300PA00X+020339Y+107189               S0      
317GND              J13   -P28  D0300PA00X+021339Y+107189               S0      
317GND              J13   -P4   D0300PA00X+020339Y+108252               S0      
317GND              J13   -P5   D0300PA00X+021339Y+108252               S0      
317P12V             CE13  -1    D0360PA00X+020503Y+112286               S0      
317P12V             CE14  -1    D0360PA00X+020512Y+120623               S0      
317GND              J14   -P4   D0300PA00X+020339Y+125752               S0      
317GND              J14   -P29  D0300PA00X+020339Y+124689               S0      
317GND              J14   -P5   D0300PA00X+021339Y+125752               S0      
317GND              J14   -P28  D0300PA00X+021339Y+124689               S0      
317P12V             VIA   -     D0100PA00X+021921Y+128727               S3      
317P12V             CE15  -1    D0360PA00X+020563Y+129910               S0      
317P12V             VIA   -     D0100PA00X+021921Y+130198               S3      
317P12V             VIA   -     D0100PA00X+021935Y+130892               S3      
317P12V             VIA   -     D0100PA00X+021921Y+129449               S3      
317P12V             VIA   -     D0100PA00X+021918Y+132429               S3      
317P12V             VIA   -     D0100PA00X+021918Y+133232               S3      
317P12V             VIA   -     D0100PA00X+021918Y+131684               S3      
317P12V             VIA   -     D0100PA00X+021918Y+133984               S3      
317P12V             CE16  -1    D0360PA00X+020433Y+138097               S0      
317GND              J15   -P4   D0300PA00X+020339Y+143252               S0      
317GND              J15   -P29  D0300PA00X+020339Y+142189               S0      
317GND              J15   -P5   D0300PA00X+021339Y+143252               S0      
317GND              J15   -P28  D0300PA00X+021339Y+142189               S0      
317P12V             CE17  -1    D0360PA00X+020324Y+147416               S0      
317P12V             CE18  -1    D0360PA00X+020486Y+155728               S0      
317GND              J16   -P29  D0300PA00X+020339Y+159689               S0      
317GND              J16   -P28  D0300PA00X+021339Y+159689               S0      
317GND              J16   -P4   D0300PA00X+020339Y+160752               S0      
317GND              J16   -P5   D0300PA00X+021339Y+160752               S0      
317P12V             CE19  -1    D0360PA00X+020592Y+164818               S0      
317GND              VIA   -     D0100PA00X+021913Y+166317               S3      
317GND              VIA   -     D0100PA00X+021913Y+167039               S3      
317GND              VIA   -     D0100PA00X+021913Y+168447               S3      
317GND              VIA   -     D0100PA00X+021913Y+167787               S3      
317GND              VIA   -     D0100PA00X+021896Y+169238               S3      
317GND              VIA   -     D0100PA00X+021896Y+169983               S3      
317GND              VIA   -     D0100PA00X+021896Y+170786               S3      
317GND              VIA   -     D0100PA00X+021896Y+171538               S3      
317P12V             CE20  -1    D0360PA00X+020539Y+173135               S0      
317GND              J17   -P29  D0300PA00X+020339Y+177189               S0      
317GND              J17   -P28  D0300PA00X+021339Y+177189               S0      
317GND              J17   -P4   D0300PA00X+020339Y+178252               S0      
317GND              J17   -P5   D0300PA00X+021339Y+178252               S0      
317P12V             CE22  -1    D0360PA00X+020531Y+182323               S0      
317P12V             CE21  -1    D0360PA00X+020407Y+190042               S0      
317GND              J18   -P4   D0300PA00X+020339Y+195752               S0      
317GND              J18   -P29  D0300PA00X+020339Y+194689               S0      
317GND              J18   -P5   D0300PA00X+021339Y+195752               S0      
317GND              J18   -P28  D0300PA00X+021339Y+194689               S0      
317P12V             CE23  -1    D0360PA00X+020591Y+199873               S0      
317P12V             CE24  -1    D0360PA00X+020531Y+204339               S0      
317GND              VIA   -     D0100PA00X+020999Y+208361               S3      
317GND              VIA   -     D0100PA00X+022522Y+000300               S3      
317GND              J7    -P6   D0300PA00X+022339Y+003252               S0      
317GND              J7    -P27  D0300PA00X+022339Y+002189               S0      
317GND              J7    -P7   D0300PA00X+023339Y+003252               S0      
317GND              J7    -P26  D0300PA00X+023339Y+002189               S0      
317GND              J7    -P8   D0300PA00X+024339Y+003252               S0      
317GND              J7    -P25  D0300PA00X+024339Y+002189               S0      
317GND              VIA   -     D0100PA00X+023796Y+005700               S3      
317GND              VIA   -     D0100PA00X+024096Y+005700               S3      
317GND              VIA   -     D0100PA00X+023796Y+006448               S3      
317GND              VIA   -     D0100PA00X+023778Y+007900               S3      
317GND              VIA   -     D0100PA00X+023796Y+007108               S3      
317GND              VIA   -     D0100PA00X+024096Y+007108               S3      
317GND              VIA   -     D0100PA00X+024078Y+007900               S3      
317GND              VIA   -     D0100PA00X+024096Y+006448               S3      
317GND              VIA   -     D0100PA00X+023778Y+009448               S3      
317GND              VIA   -     D0100PA00X+023778Y+010199               S3      
317GND              VIA   -     D0100PA00X+023778Y+008644               S3      
317GND              VIA   -     D0100PA00X+024078Y+008644               S3      
317GND              VIA   -     D0100PA00X+024078Y+010199               S3      
317GND              VIA   -     D0100PA00X+024078Y+009448               S3      
317P12V             VIA   -     D0100PA00X+023874Y+015396               S3      
317P12V             VIA   -     D0100PA00X+022770Y+015396               S3      
317P12V             VIA   -     D0100PA00X+023874Y+017013               S3      
317P12V             VIA   -     D0100PA00X+023874Y+016169               S3      
317P12V             VIA   -     D0100PA00X+022770Y+017013               S3      
317P12V             VIA   -     D0100PA00X+022770Y+016169               S3      
317P12V             VIA   -     D0100PA00X+022770Y+016469               S3      
317P12V             VIA   -     D0100PA00X+022770Y+017313               S3      
317P12V             VIA   -     D0100PA00X+023874Y+016469               S3      
317P12V             VIA   -     D0100PA00X+023874Y+017313               S3      
317P12V             VIA   -     D0100PA00X+022770Y+015696               S3      
317P12V             VIA   -     D0100PA00X+023874Y+015696               S3      
317GND              J8    -P27  D0300PA00X+022339Y+019689               S0      
317GND              J8    -P26  D0300PA00X+023339Y+019689               S0      
317GND              J8    -P25  D0300PA00X+024339Y+019689               S0      
317GND              J8    -P6   D0300PA00X+022339Y+020752               S0      
317GND              J8    -P7   D0300PA00X+023339Y+020752               S0      
317GND              J8    -P8   D0300PA00X+024339Y+020752               S0      
317GND              VIA   -     D0100PA00X+024103Y+024500               S3      
317GND              VIA   -     D0100PA00X+023354Y+024500               S3      
317GND              VIA   -     D0100PA00X+022471Y+023778               S3      
317GND              VIA   -     D0100PA00X+022471Y+024500               S3      
317GND              VIA   -     D0100PA00X+022771Y+024500               S3      
317GND              VIA   -     D0100PA00X+022771Y+023778               S3      
317GND              VIA   -     D0100PA00X+023654Y+024500               S3      
317GND              VIA   -     D0100PA00X+024103Y+025907               S3      
317GND              VIA   -     D0100PA00X+024086Y+026699               S3      
317GND              VIA   -     D0100PA00X+024086Y+027444               S3      
317GND              VIA   -     D0100PA00X+024103Y+025248               S3      
317GND              VIA   -     D0100PA00X+023354Y+025907               S3      
317GND              VIA   -     D0100PA00X+023337Y+026699               S3      
317GND              VIA   -     D0100PA00X+023337Y+027444               S3      
317GND              VIA   -     D0100PA00X+022471Y+025907               S3      
317GND              VIA   -     D0100PA00X+022454Y+026699               S3      
317GND              VIA   -     D0100PA00X+022454Y+027444               S3      
317GND              VIA   -     D0100PA00X+023354Y+025248               S3      
317GND              VIA   -     D0100PA00X+022471Y+025248               S3      
317GND              VIA   -     D0100PA00X+022771Y+025248               S3      
317GND              VIA   -     D0100PA00X+023654Y+025248               S3      
317GND              VIA   -     D0100PA00X+022754Y+027444               S3      
317GND              VIA   -     D0100PA00X+022754Y+026699               S3      
317GND              VIA   -     D0100PA00X+022771Y+025907               S3      
317GND              VIA   -     D0100PA00X+023637Y+027444               S3      
317GND              VIA   -     D0100PA00X+023637Y+026699               S3      
317GND              VIA   -     D0100PA00X+023654Y+025907               S3      
317GND              VIA   -     D0100PA00X+024086Y+028999               S3      
317GND              VIA   -     D0100PA00X+024086Y+028247               S3      
317GND              VIA   -     D0100PA00X+023337Y+028999               S3      
317GND              VIA   -     D0100PA00X+022454Y+028999               S3      
317GND              VIA   -     D0100PA00X+023337Y+028247               S3      
317GND              VIA   -     D0100PA00X+022454Y+028247               S3      
317GND              VIA   -     D0100PA00X+022754Y+028247               S3      
317GND              VIA   -     D0100PA00X+023637Y+028247               S3      
317GND              VIA   -     D0100PA00X+022754Y+028999               S3      
317GND              VIA   -     D0100PA00X+023637Y+028999               S3      
317GND              J9    -P27  D0300PA00X+022339Y+037189               S0      
317GND              J9    -P26  D0300PA00X+023339Y+037189               S0      
317GND              J9    -P25  D0300PA00X+024339Y+037189               S0      
317GND              J9    -P6   D0300PA00X+022339Y+038252               S0      
317GND              J9    -P7   D0300PA00X+023339Y+038252               S0      
317GND              J9    -P8   D0300PA00X+024339Y+038252               S0      
317P12V             VIA   -     D0100PA00X+023975Y+040739               S3      
317P12V             VIA   -     D0100PA00X+023975Y+039688               S3      
317P12V             VIA   -     D0100PA00X+023975Y+041790               S3      
317P12V             VIA   -     D0100PA00X+023975Y+039988               S3      
317P12V             VIA   -     D0100PA00X+023975Y+041039               S3      
317P12V             VIA   -     D0100PA00X+023975Y+042090               S3      
317GND              VIA   -     D0100PA00X+022955Y+046108               S3      
317GND              VIA   -     D0100PA00X+023255Y+046108               S3      
317GND              VIA   -     D0100PA00X+023837Y+048238               S3      
317GND              VIA   -     D0100PA00X+023820Y+049030               S3      
317GND              VIA   -     D0100PA00X+022955Y+048238               S3      
317GND              VIA   -     D0100PA00X+022938Y+049030               S3      
317GND              VIA   -     D0100PA00X+023837Y+046830               S3      
317GND              VIA   -     D0100PA00X+023837Y+047579               S3      
317GND              VIA   -     D0100PA00X+022955Y+046830               S3      
317GND              VIA   -     D0100PA00X+022955Y+047579               S3      
317GND              VIA   -     D0100PA00X+023255Y+047579               S3      
317GND              VIA   -     D0100PA00X+023255Y+046830               S3      
317GND              VIA   -     D0100PA00X+024137Y+047579               S3      
317GND              VIA   -     D0100PA00X+024137Y+046830               S3      
317GND              VIA   -     D0100PA00X+023238Y+049030               S3      
317GND              VIA   -     D0100PA00X+023255Y+048238               S3      
317GND              VIA   -     D0100PA00X+024120Y+049030               S3      
317GND              VIA   -     D0100PA00X+024137Y+048238               S3      
317GND              VIA   -     D0100PA00X+023820Y+051330               S3      
317GND              VIA   -     D0100PA00X+022938Y+051330               S3      
317GND              VIA   -     D0100PA00X+023820Y+049774               S3      
317GND              VIA   -     D0100PA00X+022938Y+049774               S3      
317GND              VIA   -     D0100PA00X+023820Y+050578               S3      
317GND              VIA   -     D0100PA00X+022938Y+050578               S3      
317GND              VIA   -     D0100PA00X+023238Y+050578               S3      
317GND              VIA   -     D0100PA00X+024120Y+050578               S3      
317GND              VIA   -     D0100PA00X+023238Y+049774               S3      
317GND              VIA   -     D0100PA00X+024120Y+049774               S3      
317GND              VIA   -     D0100PA00X+023238Y+051330               S3      
317GND              VIA   -     D0100PA00X+024120Y+051330               S3      
317GND              J10   -P6   D0300PA00X+022339Y+055752               S0      
317GND              J10   -P27  D0300PA00X+022339Y+054689               S0      
317GND              J10   -P7   D0300PA00X+023339Y+055752               S0      
317GND              J10   -P26  D0300PA00X+023339Y+054689               S0      
317GND              J10   -P8   D0300PA00X+024339Y+055752               S0      
317GND              J10   -P25  D0300PA00X+024339Y+054689               S0      
317GND              VIA   -     D0100PA00X+022796Y+060811               S3      
317GND              VIA   -     D0100PA00X+023539Y+060811               S3      
317GND              VIA   -     D0100PA00X+022796Y+060151               S3      
317GND              VIA   -     D0100PA00X+023539Y+060151               S3      
317GND              VIA   -     D0100PA00X+023539Y+059403               S3      
317GND              VIA   -     D0100PA00X+022796Y+059403               S3      
317GND              VIA   -     D0100PA00X+023096Y+059403               S3      
317GND              VIA   -     D0100PA00X+023839Y+059403               S3      
317GND              VIA   -     D0100PA00X+023839Y+060151               S3      
317GND              VIA   -     D0100PA00X+023096Y+060151               S3      
317GND              VIA   -     D0100PA00X+023839Y+060811               S3      
317GND              VIA   -     D0100PA00X+023096Y+060811               S3      
317GND              VIA   -     D0100PA00X+022779Y+063151               S3      
317GND              VIA   -     D0100PA00X+023522Y+063151               S3      
317GND              VIA   -     D0100PA00X+022779Y+062347               S3      
317GND              VIA   -     D0100PA00X+023522Y+062347               S3      
317GND              VIA   -     D0100PA00X+022779Y+061603               S3      
317GND              VIA   -     D0100PA00X+023522Y+061603               S3      
317GND              VIA   -     D0100PA00X+023822Y+061603               S3      
317GND              VIA   -     D0100PA00X+023079Y+061603               S3      
317GND              VIA   -     D0100PA00X+023822Y+062347               S3      
317GND              VIA   -     D0100PA00X+023079Y+062347               S3      
317GND              VIA   -     D0100PA00X+023822Y+063151               S3      
317GND              VIA   -     D0100PA00X+023079Y+063151               S3      
317GND              VIA   -     D0100PA00X+022779Y+063902               S3      
317GND              VIA   -     D0100PA00X+023522Y+063902               S3      
317GND              VIA   -     D0100PA00X+023822Y+063902               S3      
317GND              VIA   -     D0100PA00X+023079Y+063902               S3      
317GND              J11   -P6   D0300PA00X+022339Y+073252               S0      
317GND              J11   -P27  D0300PA00X+022339Y+072189               S0      
317GND              J11   -P7   D0300PA00X+023339Y+073252               S0      
317GND              J11   -P26  D0300PA00X+023339Y+072189               S0      
317GND              J11   -P8   D0300PA00X+024339Y+073252               S0      
317GND              J11   -P25  D0300PA00X+024339Y+072189               S0      
317P12V             VIA   -     D0100PA00X+023401Y+075478               S3      
317P12V             VIA   -     D0100PA00X+023701Y+075478               S3      
317P12V             VIA   -     D0100PA00X+023401Y+076251               S3      
317P12V             VIA   -     D0100PA00X+023401Y+077095               S3      
317P12V             VIA   -     D0100PA00X+023701Y+077095               S3      
317P12V             VIA   -     D0100PA00X+023701Y+076251               S3      
317P12V             VIA   -     D0100PA00X+024140Y+086289               S3      
317P12V             VIA   -     D0100PA00X+024140Y+085516               S3      
317P12V             VIA   -     D0100PA00X+024140Y+087133               S3      
317P12V             VIA   -     D0100PA00X+023840Y+087133               S3      
317P12V             VIA   -     D0100PA00X+023840Y+085516               S3      
317P12V             VIA   -     D0100PA00X+023840Y+086289               S3      
317GND              J12   -P27  D0300PA00X+022339Y+089689               S0      
317GND              J12   -P26  D0300PA00X+023339Y+089689               S0      
317GND              J12   -P25  D0300PA00X+024339Y+089689               S0      
317GND              J12   -P6   D0300PA00X+022339Y+090752               S0      
317GND              J12   -P7   D0300PA00X+023339Y+090752               S0      
317GND              J12   -P8   D0300PA00X+024339Y+090752               S0      
317GND              VIA   -     D0100PA00X+023134Y+095967               S3      
317GND              VIA   -     D0100PA00X+023877Y+095967               S3      
317GND              VIA   -     D0100PA00X+023877Y+096716               S3      
317GND              VIA   -     D0100PA00X+023877Y+097375               S3      
317GND              VIA   -     D0100PA00X+023134Y+097375               S3      
317GND              VIA   -     D0100PA00X+023134Y+096716               S3      
317GND              VIA   -     D0100PA00X+023877Y+095245               S3      
317GND              VIA   -     D0100PA00X+023134Y+095245               S3      
317GND              VIA   -     D0100PA00X+023434Y+095245               S3      
317GND              VIA   -     D0100PA00X+024177Y+095245               S3      
317GND              VIA   -     D0100PA00X+023434Y+096716               S3      
317GND              VIA   -     D0100PA00X+023434Y+097375               S3      
317GND              VIA   -     D0100PA00X+024177Y+097375               S3      
317GND              VIA   -     D0100PA00X+024177Y+096716               S3      
317GND              VIA   -     D0100PA00X+024177Y+095967               S3      
317GND              VIA   -     D0100PA00X+023434Y+095967               S3      
317GND              VIA   -     D0100PA00X+023860Y+098167               S3      
317GND              VIA   -     D0100PA00X+023117Y+098167               S3      
317GND              VIA   -     D0100PA00X+023860Y+099715               S3      
317GND              VIA   -     D0100PA00X+023860Y+098911               S3      
317GND              VIA   -     D0100PA00X+023117Y+099715               S3      
317GND              VIA   -     D0100PA00X+023117Y+098911               S3      
317GND              VIA   -     D0100PA00X+023417Y+098911               S3      
317GND              VIA   -     D0100PA00X+023417Y+099715               S3      
317GND              VIA   -     D0100PA00X+024160Y+098911               S3      
317GND              VIA   -     D0100PA00X+024160Y+099715               S3      
317GND              VIA   -     D0100PA00X+023417Y+098167               S3      
317GND              VIA   -     D0100PA00X+024160Y+098167               S3      
317GND              VIA   -     D0100PA00X+023860Y+100467               S3      
317GND              VIA   -     D0100PA00X+023117Y+100467               S3      
317GND              VIA   -     D0100PA00X+023417Y+100467               S3      
317GND              VIA   -     D0100PA00X+024160Y+100467               S3      
317GND              J13   -P27  D0300PA00X+022339Y+107189               S0      
317GND              J13   -P26  D0300PA00X+023339Y+107189               S0      
317GND              J13   -P25  D0300PA00X+024339Y+107189               S0      
317GND              J13   -P6   D0300PA00X+022339Y+108252               S0      
317GND              J13   -P7   D0300PA00X+023339Y+108252               S0      
317GND              J13   -P8   D0300PA00X+024339Y+108252               S0      
317P12V             VIA   -     D0100PA00X+023571Y+112490               S3      
317P12V             VIA   -     D0100PA00X+023571Y+113542               S3      
317P12V             VIA   -     D0100PA00X+023271Y+113542               S3      
317P12V             VIA   -     D0100PA00X+023271Y+112490               S3      
317P12V             VIA   -     D0100PA00X+024268Y+113542               S3      
317P12V             VIA   -     D0100PA00X+024268Y+112490               S3      
317P12V             VIA   -     D0100PA00X+023571Y+114592               S3      
317P12V             VIA   -     D0100PA00X+023271Y+114592               S3      
317P12V             VIA   -     D0100PA00X+024268Y+114592               S3      
317GND              VIA   -     D0100PA00X+023566Y+121530               S3      
317GND              VIA   -     D0100PA00X+022823Y+121530               S3      
317GND              VIA   -     D0100PA00X+023566Y+120778               S3      
317GND              VIA   -     D0100PA00X+023566Y+119974               S3      
317GND              VIA   -     D0100PA00X+022823Y+120778               S3      
317GND              VIA   -     D0100PA00X+022823Y+119974               S3      
317GND              VIA   -     D0100PA00X+023123Y+119974               S3      
317GND              VIA   -     D0100PA00X+023123Y+120778               S3      
317GND              VIA   -     D0100PA00X+023866Y+119974               S3      
317GND              VIA   -     D0100PA00X+023866Y+120778               S3      
317GND              VIA   -     D0100PA00X+023123Y+121530               S3      
317GND              VIA   -     D0100PA00X+023866Y+121530               S3      
317GND              J14   -P6   D0300PA00X+022339Y+125752               S0      
317GND              J14   -P27  D0300PA00X+022339Y+124689               S0      
317GND              J14   -P7   D0300PA00X+023339Y+125752               S0      
317GND              J14   -P26  D0300PA00X+023339Y+124689               S0      
317GND              J14   -P8   D0300PA00X+024339Y+125752               S0      
317GND              J14   -P25  D0300PA00X+024339Y+124689               S0      
317P12V             VIA   -     D0100PA00X+022664Y+128727               S3      
317P12V             VIA   -     D0100PA00X+022221Y+128727               S3      
317P12V             VIA   -     D0100PA00X+022964Y+128727               S3      
317P12V             VIA   -     D0100PA00X+022664Y+130198               S3      
317P12V             VIA   -     D0100PA00X+023547Y+130198               S3      
317P12V             VIA   -     D0100PA00X+022678Y+130892               S3      
317P12V             VIA   -     D0100PA00X+023560Y+130892               S3      
317P12V             VIA   -     D0100PA00X+024296Y+130198               S3      
317P12V             VIA   -     D0100PA00X+024310Y+130892               S3      
317P12V             VIA   -     D0100PA00X+022664Y+129449               S3      
317P12V             VIA   -     D0100PA00X+023547Y+129449               S3      
317P12V             VIA   -     D0100PA00X+024296Y+129449               S3      
317P12V             VIA   -     D0100PA00X+022221Y+129449               S3      
317P12V             VIA   -     D0100PA00X+022235Y+130892               S3      
317P12V             VIA   -     D0100PA00X+022221Y+130198               S3      
317P12V             VIA   -     D0100PA00X+023847Y+129449               S3      
317P12V             VIA   -     D0100PA00X+022964Y+129449               S3      
317P12V             VIA   -     D0100PA00X+023860Y+130892               S3      
317P12V             VIA   -     D0100PA00X+022978Y+130892               S3      
317P12V             VIA   -     D0100PA00X+023847Y+130198               S3      
317P12V             VIA   -     D0100PA00X+022964Y+130198               S3      
317P12V             VIA   -     D0100PA00X+022661Y+132429               S3      
317P12V             VIA   -     D0100PA00X+023543Y+132429               S3      
317P12V             VIA   -     D0100PA00X+022661Y+133232               S3      
317P12V             VIA   -     D0100PA00X+023543Y+133232               S3      
317P12V             VIA   -     D0100PA00X+024293Y+132429               S3      
317P12V             VIA   -     D0100PA00X+024293Y+133232               S3      
317P12V             VIA   -     D0100PA00X+022661Y+131684               S3      
317P12V             VIA   -     D0100PA00X+023543Y+131684               S3      
317P12V             VIA   -     D0100PA00X+024293Y+131684               S3      
317P12V             VIA   -     D0100PA00X+022218Y+131684               S3      
317P12V             VIA   -     D0100PA00X+022218Y+133232               S3      
317P12V             VIA   -     D0100PA00X+022218Y+132429               S3      
317P12V             VIA   -     D0100PA00X+023843Y+131684               S3      
317P12V             VIA   -     D0100PA00X+022961Y+131684               S3      
317P12V             VIA   -     D0100PA00X+023843Y+133232               S3      
317P12V             VIA   -     D0100PA00X+022961Y+133232               S3      
317P12V             VIA   -     D0100PA00X+023843Y+132429               S3      
317P12V             VIA   -     D0100PA00X+022961Y+132429               S3      
317P12V             VIA   -     D0100PA00X+022661Y+133984               S3      
317P12V             VIA   -     D0100PA00X+023543Y+133984               S3      
317P12V             VIA   -     D0100PA00X+024293Y+133984               S3      
317P12V             VIA   -     D0100PA00X+022218Y+133984               S3      
317P12V             VIA   -     D0100PA00X+023843Y+133984               S3      
317P12V             VIA   -     D0100PA00X+022961Y+133984               S3      
317GND              J15   -P6   D0300PA00X+022339Y+143252               S0      
317GND              J15   -P27  D0300PA00X+022339Y+142189               S0      
317GND              J15   -P7   D0300PA00X+023339Y+143252               S0      
317GND              J15   -P26  D0300PA00X+023339Y+142189               S0      
317GND              J15   -P8   D0300PA00X+024339Y+143252               S0      
317GND              J15   -P25  D0300PA00X+024339Y+142189               S0      
317GND              J16   -P27  D0300PA00X+022339Y+159689               S0      
317GND              J16   -P26  D0300PA00X+023339Y+159689               S0      
317GND              J16   -P25  D0300PA00X+024339Y+159689               S0      
317GND              J16   -P6   D0300PA00X+022339Y+160752               S0      
317GND              J16   -P7   D0300PA00X+023339Y+160752               S0      
317GND              J16   -P8   D0300PA00X+024339Y+160752               S0      
317GND              VIA   -     D0100PA00X+023538Y+167039               S3      
317GND              VIA   -     D0100PA00X+022656Y+166317               S3      
317GND              VIA   -     D0100PA00X+022656Y+167039               S3      
317GND              VIA   -     D0100PA00X+022213Y+167039               S3      
317GND              VIA   -     D0100PA00X+022956Y+167039               S3      
317GND              VIA   -     D0100PA00X+022956Y+166317               S3      
317GND              VIA   -     D0100PA00X+023838Y+167039               S3      
317GND              VIA   -     D0100PA00X+022213Y+166317               S3      
317GND              VIA   -     D0100PA00X+024288Y+167039               S3      
317GND              VIA   -     D0100PA00X+023538Y+167787               S3      
317GND              VIA   -     D0100PA00X+023521Y+169238               S3      
317GND              VIA   -     D0100PA00X+023538Y+168447               S3      
317GND              VIA   -     D0100PA00X+022656Y+168447               S3      
317GND              VIA   -     D0100PA00X+022656Y+167787               S3      
317GND              VIA   -     D0100PA00X+022639Y+169238               S3      
317GND              VIA   -     D0100PA00X+022196Y+169238               S3      
317GND              VIA   -     D0100PA00X+022213Y+167787               S3      
317GND              VIA   -     D0100PA00X+022213Y+168447               S3      
317GND              VIA   -     D0100PA00X+022939Y+169238               S3      
317GND              VIA   -     D0100PA00X+022956Y+167787               S3      
317GND              VIA   -     D0100PA00X+022956Y+168447               S3      
317GND              VIA   -     D0100PA00X+023838Y+168447               S3      
317GND              VIA   -     D0100PA00X+023821Y+169238               S3      
317GND              VIA   -     D0100PA00X+023838Y+167787               S3      
317GND              VIA   -     D0100PA00X+024288Y+167787               S3      
317GND              VIA   -     D0100PA00X+024288Y+168447               S3      
317GND              VIA   -     D0100PA00X+024271Y+169238               S3      
317GND              VIA   -     D0100PA00X+023521Y+169983               S3      
317GND              VIA   -     D0100PA00X+022639Y+169983               S3      
317GND              VIA   -     D0100PA00X+023521Y+171538               S3      
317GND              VIA   -     D0100PA00X+023521Y+170786               S3      
317GND              VIA   -     D0100PA00X+022639Y+170786               S3      
317GND              VIA   -     D0100PA00X+022639Y+171538               S3      
317GND              VIA   -     D0100PA00X+022196Y+171538               S3      
317GND              VIA   -     D0100PA00X+022196Y+170786               S3      
317GND              VIA   -     D0100PA00X+022939Y+171538               S3      
317GND              VIA   -     D0100PA00X+022939Y+170786               S3      
317GND              VIA   -     D0100PA00X+023821Y+170786               S3      
317GND              VIA   -     D0100PA00X+023821Y+171538               S3      
317GND              VIA   -     D0100PA00X+022196Y+169983               S3      
317GND              VIA   -     D0100PA00X+022939Y+169983               S3      
317GND              VIA   -     D0100PA00X+023821Y+169983               S3      
317GND              VIA   -     D0100PA00X+024271Y+169983               S3      
317GND              VIA   -     D0100PA00X+024271Y+170786               S3      
317GND              VIA   -     D0100PA00X+024271Y+171538               S3      
317GND              J17   -P27  D0300PA00X+022339Y+177189               S0      
317GND              J17   -P26  D0300PA00X+023339Y+177189               S0      
317GND              J17   -P25  D0300PA00X+024339Y+177189               S0      
317GND              J17   -P6   D0300PA00X+022339Y+178252               S0      
317GND              J17   -P7   D0300PA00X+023339Y+178252               S0      
317GND              J17   -P8   D0300PA00X+024339Y+178252               S0      
317GND              J18   -P6   D0300PA00X+022339Y+195752               S0      
317GND              J18   -P27  D0300PA00X+022339Y+194689               S0      
317GND              J18   -P7   D0300PA00X+023339Y+195752               S0      
317GND              J18   -P26  D0300PA00X+023339Y+194689               S0      
317GND              J18   -P8   D0300PA00X+024339Y+195752               S0      
317GND              J18   -P25  D0300PA00X+024339Y+194689               S0      
317P12V             VIA   -     D0100PA00X+022657Y+203148               S3      
317P12V             VIA   -     D0100PA00X+023654Y+203148               S3      
317P12V             VIA   -     D0100PA00X+022657Y+202097               S3      
317P12V             VIA   -     D0100PA00X+023654Y+202097               S3      
317P12V             VIA   -     D0100PA00X+024258Y+202097               S3      
317P12V             VIA   -     D0100PA00X+024258Y+203148               S3      
317P12V             VIA   -     D0100PA00X+023154Y+202097               S3      
317P12V             VIA   -     D0100PA00X+022157Y+202097               S3      
317P12V             VIA   -     D0100PA00X+023154Y+203148               S3      
317P12V             VIA   -     D0100PA00X+022157Y+203148               S3      
317P12V             VIA   -     D0100PA00X+022657Y+205905               S3      
317P12V             VIA   -     D0100PA00X+023654Y+205132               S3      
317P12V             VIA   -     D0100PA00X+023654Y+205905               S3      
317P12V             VIA   -     D0100PA00X+022657Y+204199               S3      
317P12V             VIA   -     D0100PA00X+022657Y+205132               S3      
317P12V             VIA   -     D0100PA00X+023654Y+204199               S3      
317P12V             VIA   -     D0100PA00X+024258Y+205905               S3      
317P12V             VIA   -     D0100PA00X+024258Y+205132               S3      
317P12V             VIA   -     D0100PA00X+024258Y+204199               S3      
317P12V             VIA   -     D0100PA00X+023154Y+204199               S3      
317P12V             VIA   -     D0100PA00X+022157Y+205132               S3      
317P12V             VIA   -     D0100PA00X+022157Y+204199               S3      
317P12V             VIA   -     D0100PA00X+023154Y+205905               S3      
317P12V             VIA   -     D0100PA00X+023154Y+205132               S3      
317P12V             VIA   -     D0100PA00X+022157Y+205905               S3      
317P12V             VIA   -     D0100PA00X+023654Y+206749               S3      
317P12V             VIA   -     D0100PA00X+022657Y+206749               S3      
317P12V             VIA   -     D0100PA00X+024258Y+206749               S3      
317P12V             VIA   -     D0100PA00X+022157Y+206749               S3      
317P12V             VIA   -     D0100PA00X+023154Y+206749               S3      
317P12V             J7    -P24  D0300PA00X+025339Y+002189               S0      
317P12V             J7    -P9   D0300PA00X+025339Y+003252               S0      
317P12V             J7    -P23  D0300PA00X+026339Y+002189               S0      
317P12V             J7    -P10  D0300PA00X+026339Y+003252               S0      
317P12V             VIA   -     D0100PA00X+025657Y+005494               S3      
317P12V             VIA   -     D0100PA00X+026410Y+005494               S3      
317P12V             VIA   -     D0100PA00X+025657Y+004557               S3      
317P12V             VIA   -     D0100PA00X+026410Y+004557               S3      
317P12V             VIA   -     D0100PA00X+026410Y+004857               S3      
317P12V             VIA   -     D0100PA00X+025657Y+004857               S3      
317GND              VIA   -     D0100PA00X+024545Y+005700               S3      
317GND              VIA   -     D0100PA00X+024845Y+005700               S3      
317P12V             VIA   -     D0100PA00X+025657Y+006545               S3      
317P12V             VIA   -     D0100PA00X+026410Y+006545               S3      
317P12V             VIA   -     D0100PA00X+026410Y+005794               S3      
317P12V             VIA   -     D0100PA00X+025657Y+005794               S3      
317P12V             VIA   -     D0100PA00X+026410Y+006845               S3      
317P12V             VIA   -     D0100PA00X+025657Y+006845               S3      
317GND              VIA   -     D0100PA00X+024545Y+006448               S3      
317GND              VIA   -     D0100PA00X+024528Y+007900               S3      
317GND              VIA   -     D0100PA00X+024545Y+007108               S3      
317GND              VIA   -     D0100PA00X+024845Y+007108               S3      
317GND              VIA   -     D0100PA00X+024828Y+007900               S3      
317GND              VIA   -     D0100PA00X+024845Y+006448               S3      
317GND              VIA   -     D0100PA00X+024528Y+009448               S3      
317GND              VIA   -     D0100PA00X+024528Y+010199               S3      
317GND              VIA   -     D0100PA00X+024528Y+008644               S3      
317GND              VIA   -     D0100PA00X+024828Y+008644               S3      
317GND              VIA   -     D0100PA00X+024828Y+010199               S3      
317GND              VIA   -     D0100PA00X+024828Y+009448               S3      
327P12V             R111  -2          A01X+026469Y+012823X0180Y0200R180 S2      
327NNAME10041       R111  -1          A01X+026154Y+012823X0180Y0200R180 S2      
327GND              R112  -2          A01X+026493Y+011556X0180Y0200R180 S2      
327NNAME10029       R112  -1          A01X+026178Y+011556X0180Y0200R180 S2      
317GND              VIA   -     D0100PA00X+026763Y+011556               S3      
317NNAME10041       VIA   -     D0100PA00X+025695Y+012828               S1      
317NNAME10029       VIA   -     D0100PA00X+025713Y+011556               S1      
327GND              C14   -2          A01X+026309Y+015126X0180Y0200R090 S2      
327GND              C13   -2          A01X+026742Y+015126X0180Y0200R090 S2      
317GND              VIA   -     D0100PA00X+026742Y+014754               S3      
317GND              VIA   -     D0100PA00X+026309Y+014768               S1      
327P12V             C14   -1          A01X+026309Y+015441X0180Y0200R090 S2      
327P12V             C13   -1          A01X+026742Y+015441X0180Y0200R090 S2      
317P12V             VIA   -     D0100PA00X+025686Y+015396               S3      
317P12V             VIA   -     D0100PA00X+024808Y+015396               S3      
317P12V             VIA   -     D0100PA00X+025686Y+017013               S3      
317P12V             VIA   -     D0100PA00X+025686Y+016169               S3      
317P12V             VIA   -     D0100PA00X+024808Y+017013               S3      
317P12V             VIA   -     D0100PA00X+024808Y+016169               S3      
317P12V             VIA   -     D0100PA00X+024808Y+016469               S3      
317P12V             VIA   -     D0100PA00X+024808Y+017313               S3      
317P12V             VIA   -     D0100PA00X+025686Y+016469               S3      
317P12V             VIA   -     D0100PA00X+025686Y+017313               S3      
317P12V             VIA   -     D0100PA00X+024808Y+015696               S3      
317P12V             VIA   -     D0100PA00X+025686Y+015696               S3      
317P12V             J8    -P24  D0300PA00X+025339Y+019689               S0      
317P12V             J8    -P23  D0300PA00X+026339Y+019689               S0      
317P12V             J8    -P9   D0300PA00X+025339Y+020752               S0      
317P12V             J8    -P10  D0300PA00X+026339Y+020752               S0      
317P12V             VIA   -     D0100PA00X+026460Y+022166               S3      
317P12V             VIA   -     D0100PA00X+025282Y+022166               S3      
317P12V             VIA   -     D0100PA00X+025582Y+022166               S3      
317P12V             VIA   -     D0100PA00X+026160Y+022166               S3      
317P12V             VIA   -     D0100PA00X+026460Y+024268               S3      
317P12V             VIA   -     D0100PA00X+026460Y+023218               S3      
317P12V             VIA   -     D0100PA00X+025282Y+024268               S3      
317P12V             VIA   -     D0100PA00X+025282Y+023218               S3      
317P12V             VIA   -     D0100PA00X+025582Y+023218               S3      
317P12V             VIA   -     D0100PA00X+025582Y+024268               S3      
317P12V             VIA   -     D0100PA00X+026160Y+023218               S3      
317P12V             VIA   -     D0100PA00X+026160Y+024268               S3      
317GND              VIA   -     D0100PA00X+024403Y+024500               S3      
317P12V             VIA   -     D0100PA00X+026460Y+026819               S3      
317P12V             VIA   -     D0100PA00X+026460Y+025975               S3      
317P12V             VIA   -     D0100PA00X+026460Y+025202               S3      
317P12V             VIA   -     D0100PA00X+025282Y+026819               S3      
317P12V             VIA   -     D0100PA00X+025282Y+025202               S3      
317P12V             VIA   -     D0100PA00X+025282Y+025975               S3      
317P12V             VIA   -     D0100PA00X+025582Y+025975               S3      
317P12V             VIA   -     D0100PA00X+025582Y+025202               S3      
317P12V             VIA   -     D0100PA00X+025582Y+026819               S3      
317P12V             VIA   -     D0100PA00X+026160Y+025202               S3      
317P12V             VIA   -     D0100PA00X+026160Y+025975               S3      
317P12V             VIA   -     D0100PA00X+026160Y+026819               S3      
317GND              VIA   -     D0100PA00X+024403Y+025248               S3      
317GND              VIA   -     D0100PA00X+024386Y+027444               S3      
317GND              VIA   -     D0100PA00X+024386Y+026699               S3      
317GND              VIA   -     D0100PA00X+024403Y+025907               S3      
317GND              VIA   -     D0100PA00X+024386Y+028247               S3      
317GND              VIA   -     D0100PA00X+024386Y+028999               S3      
317P12V             J9    -P24  D0300PA00X+025339Y+037189               S0      
317P12V             J9    -P23  D0300PA00X+026339Y+037189               S0      
317P12V             J9    -P9   D0300PA00X+025339Y+038252               S0      
317P12V             J9    -P10  D0300PA00X+026339Y+038252               S0      
317P12V             VIA   -     D0100PA00X+026604Y+040715               S3      
317P12V             VIA   -     D0100PA00X+026604Y+039663               S3      
317P12V             VIA   -     D0100PA00X+026604Y+041765               S3      
317P12V             VIA   -     D0100PA00X+025757Y+039663               S3      
317P12V             VIA   -     D0100PA00X+025757Y+040715               S3      
317P12V             VIA   -     D0100PA00X+024871Y+040754               S3      
317P12V             VIA   -     D0100PA00X+024871Y+039702               S3      
317P12V             VIA   -     D0100PA00X+025757Y+041765               S3      
317P12V             VIA   -     D0100PA00X+024871Y+041804               S3      
317P12V             VIA   -     D0100PA00X+024871Y+040002               S3      
317P12V             VIA   -     D0100PA00X+024871Y+041054               S3      
317P12V             VIA   -     D0100PA00X+025757Y+041015               S3      
317P12V             VIA   -     D0100PA00X+025757Y+039963               S3      
317P12V             VIA   -     D0100PA00X+026604Y+039963               S3      
317P12V             VIA   -     D0100PA00X+026604Y+041015               S3      
317P12V             VIA   -     D0100PA00X+024871Y+042104               S3      
317P12V             VIA   -     D0100PA00X+025757Y+042065               S3      
317P12V             VIA   -     D0100PA00X+026604Y+042065               S3      
317NNAME10032       VIA   -     D0100PA00X+026572Y+046310               S1      
317GND              VIA   -     D0100PA00X+024587Y+048238               S3      
317GND              VIA   -     D0100PA00X+024570Y+049030               S3      
317GND              VIA   -     D0100PA00X+024587Y+046830               S3      
317GND              VIA   -     D0100PA00X+024587Y+047579               S3      
317GND              VIA   -     D0100PA00X+024887Y+047579               S3      
317GND              VIA   -     D0100PA00X+024887Y+046830               S3      
317GND              VIA   -     D0100PA00X+024870Y+049030               S3      
317GND              VIA   -     D0100PA00X+024887Y+048238               S3      
317NNAME10043       VIA   -     D0100PA00X+026574Y+047368               S1      
327GND              C28   -2          A01X+026452Y+050092X0180Y0200R090 S2      
327P12V             C28   -1          A01X+026452Y+050407X0180Y0200R090 S2      
317GND              VIA   -     D0100PA00X+024570Y+051330               S3      
317GND              VIA   -     D0100PA00X+024570Y+049774               S3      
317GND              VIA   -     D0100PA00X+024570Y+050578               S3      
317GND              VIA   -     D0100PA00X+024870Y+050578               S3      
317GND              VIA   -     D0100PA00X+024870Y+049774               S3      
317GND              VIA   -     D0100PA00X+024870Y+051330               S3      
317GND              VIA   -     D0100PA00X+026452Y+049734               S1      
317P12V             J10   -P24  D0300PA00X+025339Y+054689               S0      
317P12V             J10   -P9   D0300PA00X+025339Y+055752               S0      
317P12V             J10   -P23  D0300PA00X+026339Y+054689               S0      
317P12V             J10   -P10  D0300PA00X+026339Y+055752               S0      
317P12V             VIA   -     D0100PA00X+026717Y+058144               S3      
317P12V             VIA   -     D0100PA00X+026717Y+057264               S3      
317P12V             VIA   -     D0100PA00X+026417Y+057264               S3      
317P12V             VIA   -     D0100PA00X+026417Y+058144               S3      
317P12V             VIA   -     D0100PA00X+026717Y+060901               S3      
317P12V             VIA   -     D0100PA00X+026717Y+060128               S3      
317P12V             VIA   -     D0100PA00X+026717Y+059195               S3      
317P12V             VIA   -     D0100PA00X+026417Y+059195               S3      
317P12V             VIA   -     D0100PA00X+026417Y+060128               S3      
317P12V             VIA   -     D0100PA00X+026417Y+060901               S3      
317GND              VIA   -     D0100PA00X+025171Y+060811               S3      
317GND              VIA   -     D0100PA00X+025171Y+060151               S3      
317GND              VIA   -     D0100PA00X+025171Y+059403               S3      
317GND              VIA   -     D0100PA00X+024421Y+060811               S3      
317GND              VIA   -     D0100PA00X+024421Y+060151               S3      
317GND              VIA   -     D0100PA00X+024421Y+059403               S3      
317GND              VIA   -     D0100PA00X+024721Y+059403               S3      
317GND              VIA   -     D0100PA00X+024721Y+060151               S3      
317GND              VIA   -     D0100PA00X+024721Y+060811               S3      
317GND              VIA   -     D0100PA00X+025471Y+059403               S3      
317GND              VIA   -     D0100PA00X+025471Y+060151               S3      
317GND              VIA   -     D0100PA00X+025471Y+060811               S3      
317P12V             VIA   -     D0100PA00X+026717Y+061745               S3      
317P12V             VIA   -     D0100PA00X+026417Y+061745               S3      
317GND              VIA   -     D0100PA00X+026443Y+062432               S3      
317GND              VIA   -     D0100PA00X+026743Y+062432               S3      
317GND              VIA   -     D0100PA00X+025154Y+063151               S3      
317GND              VIA   -     D0100PA00X+025154Y+062347               S3      
317GND              VIA   -     D0100PA00X+025154Y+061603               S3      
317GND              VIA   -     D0100PA00X+024404Y+063151               S3      
317GND              VIA   -     D0100PA00X+024404Y+062347               S3      
317GND              VIA   -     D0100PA00X+024404Y+061603               S3      
317GND              VIA   -     D0100PA00X+024704Y+061603               S3      
317GND              VIA   -     D0100PA00X+024704Y+062347               S3      
317GND              VIA   -     D0100PA00X+024704Y+063151               S3      
317GND              VIA   -     D0100PA00X+025454Y+061603               S3      
317GND              VIA   -     D0100PA00X+025454Y+062347               S3      
317GND              VIA   -     D0100PA00X+025454Y+063151               S3      
317GND              VIA   -     D0100PA00X+025154Y+063902               S3      
317GND              VIA   -     D0100PA00X+024404Y+063902               S3      
317GND              VIA   -     D0100PA00X+024704Y+063902               S3      
317GND              VIA   -     D0100PA00X+025454Y+063902               S3      
317P12V             J11   -P24  D0300PA00X+025339Y+072189               S0      
317P12V             J11   -P9   D0300PA00X+025339Y+073252               S0      
317P12V             J11   -P23  D0300PA00X+026339Y+072189               S0      
317P12V             J11   -P10  D0300PA00X+026339Y+073252               S0      
317P12V             VIA   -     D0100PA00X+024398Y+075478               S3      
317P12V             VIA   -     D0100PA00X+025502Y+075478               S3      
317P12V             VIA   -     D0100PA00X+025802Y+075478               S3      
317P12V             VIA   -     D0100PA00X+024698Y+075478               S3      
317P12V             VIA   -     D0100PA00X+024398Y+076251               S3      
317P12V             VIA   -     D0100PA00X+024398Y+077095               S3      
317P12V             VIA   -     D0100PA00X+025502Y+076251               S3      
317P12V             VIA   -     D0100PA00X+025502Y+077095               S3      
317P12V             VIA   -     D0100PA00X+025802Y+077095               S3      
317P12V             VIA   -     D0100PA00X+025802Y+076251               S3      
317P12V             VIA   -     D0100PA00X+024698Y+077095               S3      
317P12V             VIA   -     D0100PA00X+024698Y+076251               S3      
327P12V             R119  -2          A01X+026418Y+082360X0180Y0200R180 S2      
327NNAME10044       R119  -1          A01X+026103Y+082360X0180Y0200R180 S2      
327GND              R120  -2          A01X+026434Y+081217X0180Y0200R180 S2      
327NNAME10034       R120  -1          A01X+026119Y+081217X0180Y0200R180 S2      
317NNAME10044       VIA   -     D0100PA00X+025584Y+082363               S1      
317NNAME10034       VIA   -     D0100PA00X+025569Y+081219               S1      
327GND              C42   -2          A01X+026418Y+085124X0180Y0200R090 S2      
317GND              VIA   -     D0100PA00X+026418Y+084735               S1      
327P12V             C42   -1          A01X+026418Y+085439X0180Y0200R090 S2      
317P12V             VIA   -     D0100PA00X+025317Y+085516               S3      
317P12V             VIA   -     D0100PA00X+025317Y+086289               S3      
317P12V             VIA   -     D0100PA00X+025317Y+087133               S3      
317P12V             VIA   -     D0100PA00X+025017Y+087133               S3      
317P12V             VIA   -     D0100PA00X+025017Y+086289               S3      
317P12V             VIA   -     D0100PA00X+025017Y+085516               S3      
317P12V             J12   -P24  D0300PA00X+025339Y+089689               S0      
317P12V             J12   -P23  D0300PA00X+026339Y+089689               S0      
317P12V             J12   -P9   D0300PA00X+025339Y+090752               S0      
317P12V             J12   -P10  D0300PA00X+026339Y+090752               S0      
317P12V             VIA   -     D0100PA00X+026577Y+094934               S3      
317P12V             VIA   -     D0100PA00X+026277Y+094934               S3      
317P12V             VIA   -     D0100PA00X+026577Y+096711               S3      
317P12V             VIA   -     D0100PA00X+026577Y+095986               S3      
317P12V             VIA   -     D0100PA00X+026562Y+097439               S3      
317P12V             VIA   -     D0100PA00X+026262Y+097439               S3      
317P12V             VIA   -     D0100PA00X+026277Y+095986               S3      
317P12V             VIA   -     D0100PA00X+026277Y+096711               S3      
317GND              VIA   -     D0100PA00X+025509Y+095967               S3      
317GND              VIA   -     D0100PA00X+025509Y+097375               S3      
317GND              VIA   -     D0100PA00X+025509Y+096716               S3      
317GND              VIA   -     D0100PA00X+024759Y+095967               S3      
317GND              VIA   -     D0100PA00X+024759Y+097375               S3      
317GND              VIA   -     D0100PA00X+024759Y+096716               S3      
317GND              VIA   -     D0100PA00X+025059Y+096716               S3      
317GND              VIA   -     D0100PA00X+025059Y+097375               S3      
317GND              VIA   -     D0100PA00X+025059Y+095967               S3      
317GND              VIA   -     D0100PA00X+025809Y+096716               S3      
317GND              VIA   -     D0100PA00X+025809Y+097375               S3      
317GND              VIA   -     D0100PA00X+025809Y+095967               S3      
317P12V             VIA   -     D0100PA00X+026562Y+099055               S3      
317P12V             VIA   -     D0100PA00X+026562Y+098211               S3      
317P12V             VIA   -     D0100PA00X+026262Y+098211               S3      
317P12V             VIA   -     D0100PA00X+026262Y+099055               S3      
317GND              VIA   -     D0100PA00X+025492Y+098167               S3      
317GND              VIA   -     D0100PA00X+025492Y+099715               S3      
317GND              VIA   -     D0100PA00X+025492Y+098911               S3      
317GND              VIA   -     D0100PA00X+024742Y+098167               S3      
317GND              VIA   -     D0100PA00X+024742Y+099715               S3      
317GND              VIA   -     D0100PA00X+024742Y+098911               S3      
317GND              VIA   -     D0100PA00X+025042Y+098911               S3      
317GND              VIA   -     D0100PA00X+025042Y+099715               S3      
317GND              VIA   -     D0100PA00X+025042Y+098167               S3      
317GND              VIA   -     D0100PA00X+025792Y+098911               S3      
317GND              VIA   -     D0100PA00X+025792Y+099715               S3      
317GND              VIA   -     D0100PA00X+025792Y+098167               S3      
317GND              VIA   -     D0100PA00X+025492Y+100467               S3      
317GND              VIA   -     D0100PA00X+024742Y+100467               S3      
317GND              VIA   -     D0100PA00X+025042Y+100467               S3      
317GND              VIA   -     D0100PA00X+025792Y+100467               S3      
317P12V             J13   -P24  D0300PA00X+025339Y+107189               S0      
317P12V             J13   -P23  D0300PA00X+026339Y+107189               S0      
317P12V             J13   -P9   D0300PA00X+025339Y+108252               S0      
317P12V             J13   -P10  D0300PA00X+026339Y+108252               S0      
317P12V             VIA   -     D0100PA00X+026347Y+112461               S3      
317P12V             VIA   -     D0100PA00X+026347Y+113513               S3      
317P12V             VIA   -     D0100PA00X+024568Y+112490               S3      
317P12V             VIA   -     D0100PA00X+024568Y+113542               S3      
317P12V             VIA   -     D0100PA00X+025443Y+113527               S3      
317P12V             VIA   -     D0100PA00X+025443Y+112476               S3      
317P12V             VIA   -     D0100PA00X+025143Y+112476               S3      
317P12V             VIA   -     D0100PA00X+025143Y+113527               S3      
317P12V             VIA   -     D0100PA00X+026047Y+113513               S3      
317P12V             VIA   -     D0100PA00X+026047Y+112461               S3      
317P12V             VIA   -     D0100PA00X+026347Y+114563               S3      
317P12V             VIA   -     D0100PA00X+024568Y+114592               S3      
317P12V             VIA   -     D0100PA00X+025443Y+114578               S3      
317P12V             VIA   -     D0100PA00X+025143Y+114578               S3      
317P12V             VIA   -     D0100PA00X+026047Y+114563               S3      
317GND              VIA   -     D0100PA00X+026719Y+119178               S3      
317GND              VIA   -     D0100PA00X+026256Y+119178               S1      
327GND              C55   -2          A01X+026719Y+119531X0180Y0200R090 S2      
327P12V             C55   -1          A01X+026719Y+119846X0180Y0200R090 S2      
327GND              C56   -2          A01X+026256Y+119531X0180Y0200R090 S2      
327P12V             C56   -1          A01X+026256Y+119846X0180Y0200R090 S2      
317GND              VIA   -     D0100PA00X+025198Y+121530               S3      
317GND              VIA   -     D0100PA00X+024448Y+121530               S3      
317GND              VIA   -     D0100PA00X+025198Y+120778               S3      
317GND              VIA   -     D0100PA00X+025198Y+119974               S3      
317GND              VIA   -     D0100PA00X+024448Y+120778               S3      
317GND              VIA   -     D0100PA00X+024448Y+119974               S3      
317GND              VIA   -     D0100PA00X+024748Y+119974               S3      
317GND              VIA   -     D0100PA00X+024748Y+120778               S3      
317GND              VIA   -     D0100PA00X+025498Y+119974               S3      
317GND              VIA   -     D0100PA00X+025498Y+120778               S3      
317GND              VIA   -     D0100PA00X+024748Y+121530               S3      
317GND              VIA   -     D0100PA00X+025498Y+121530               S3      
317P12V             J14   -P24  D0300PA00X+025339Y+124689               S0      
317P12V             J14   -P9   D0300PA00X+025339Y+125752               S0      
317P12V             J14   -P23  D0300PA00X+026339Y+124689               S0      
317P12V             J14   -P10  D0300PA00X+026339Y+125752               S0      
317P12V             VIA   -     D0100PA00X+025958Y+127243               S3      
317P12V             VIA   -     D0100PA00X+025958Y+128295               S3      
317P12V             VIA   -     D0100PA00X+025658Y+128295               S3      
317P12V             VIA   -     D0100PA00X+025658Y+127243               S3      
317P12V             VIA   -     D0100PA00X+026762Y+127243               S3      
317P12V             VIA   -     D0100PA00X+026762Y+128295               S3      
317P12V             VIA   -     D0100PA00X+024596Y+129449               S3      
317P12V             VIA   -     D0100PA00X+024610Y+130892               S3      
317P12V             VIA   -     D0100PA00X+024596Y+130198               S3      
317P12V             VIA   -     D0100PA00X+025958Y+129345               S3      
317P12V             VIA   -     D0100PA00X+025958Y+130279               S3      
317P12V             VIA   -     D0100PA00X+025958Y+131052               S3      
317P12V             VIA   -     D0100PA00X+025658Y+131052               S3      
317P12V             VIA   -     D0100PA00X+025658Y+130279               S3      
317P12V             VIA   -     D0100PA00X+025658Y+129345               S3      
317P12V             VIA   -     D0100PA00X+026762Y+131052               S3      
317P12V             VIA   -     D0100PA00X+026762Y+130279               S3      
317P12V             VIA   -     D0100PA00X+026762Y+129345               S3      
317P12V             VIA   -     D0100PA00X+024593Y+131684               S3      
317P12V             VIA   -     D0100PA00X+024593Y+133232               S3      
317P12V             VIA   -     D0100PA00X+024593Y+132429               S3      
317P12V             VIA   -     D0100PA00X+025958Y+131895               S3      
317P12V             VIA   -     D0100PA00X+025658Y+131895               S3      
317P12V             VIA   -     D0100PA00X+026762Y+131895               S3      
317P12V             VIA   -     D0100PA00X+024593Y+133984               S3      
317P12V             J15   -P24  D0300PA00X+025339Y+142189               S0      
317P12V             J15   -P9   D0300PA00X+025339Y+143252               S0      
317P12V             J15   -P23  D0300PA00X+026339Y+142189               S0      
317P12V             J15   -P10  D0300PA00X+026339Y+143252               S0      
317P12V             VIA   -     D0100PA00X+026094Y+154801               S3      
317P12V             VIA   -     D0100PA00X+026094Y+153414               S3      
317P12V             VIA   -     D0100PA00X+026094Y+154106               S3      
317P12V             VIA   -     D0100PA00X+026394Y+154106               S3      
317P12V             VIA   -     D0100PA00X+026394Y+153414               S3      
317P12V             VIA   -     D0100PA00X+026394Y+154801               S3      
317P12V             J16   -P24  D0300PA00X+025339Y+159689               S0      
317P12V             J16   -P23  D0300PA00X+026339Y+159689               S0      
317P12V             J16   -P9   D0300PA00X+025339Y+160752               S0      
317P12V             J16   -P10  D0300PA00X+026339Y+160752               S0      
317P12V             VIA   -     D0100PA00X+025856Y+162182               S3      
317P12V             VIA   -     D0100PA00X+026156Y+162182               S3      
317P12V             VIA   -     D0100PA00X+025856Y+164284               S3      
317P12V             VIA   -     D0100PA00X+025856Y+163234               S3      
317P12V             VIA   -     D0100PA00X+026156Y+163234               S3      
317P12V             VIA   -     D0100PA00X+026156Y+164284               S3      
317P12V             VIA   -     D0100PA00X+025856Y+166835               S3      
317P12V             VIA   -     D0100PA00X+025856Y+165991               S3      
317P12V             VIA   -     D0100PA00X+025856Y+165218               S3      
317P12V             VIA   -     D0100PA00X+026156Y+165218               S3      
317P12V             VIA   -     D0100PA00X+026156Y+165991               S3      
317P12V             VIA   -     D0100PA00X+026156Y+166835               S3      
317GND              VIA   -     D0100PA00X+024588Y+167039               S3      
317P12V             VIA   -     D0100PA00X+026276Y+169761               S3      
317P12V             VIA   -     D0100PA00X+026276Y+167659               S3      
317P12V             VIA   -     D0100PA00X+026276Y+168711               S3      
317P12V             VIA   -     D0100PA00X+025172Y+169761               S3      
317P12V             VIA   -     D0100PA00X+025172Y+168711               S3      
317P12V             VIA   -     D0100PA00X+025172Y+167659               S3      
317P12V             VIA   -     D0100PA00X+025472Y+167659               S3      
317P12V             VIA   -     D0100PA00X+025472Y+168711               S3      
317P12V             VIA   -     D0100PA00X+026576Y+168711               S3      
317P12V             VIA   -     D0100PA00X+026576Y+167659               S3      
317P12V             VIA   -     D0100PA00X+025472Y+169761               S3      
317P12V             VIA   -     D0100PA00X+026576Y+169761               S3      
317GND              VIA   -     D0100PA00X+024571Y+169238               S3      
317GND              VIA   -     D0100PA00X+024588Y+168447               S3      
317GND              VIA   -     D0100PA00X+024588Y+167787               S3      
317P12V             VIA   -     D0100PA00X+026250Y+172214               S3      
317P12V             VIA   -     D0100PA00X+026276Y+171468               S3      
317P12V             VIA   -     D0100PA00X+026276Y+170695               S3      
317P12V             VIA   -     D0100PA00X+025146Y+172214               S3      
317P12V             VIA   -     D0100PA00X+025172Y+171468               S3      
317P12V             VIA   -     D0100PA00X+025172Y+170695               S3      
317P12V             VIA   -     D0100PA00X+026576Y+170695               S3      
317P12V             VIA   -     D0100PA00X+025472Y+170695               S3      
317P12V             VIA   -     D0100PA00X+025472Y+171468               S3      
317P12V             VIA   -     D0100PA00X+026576Y+171468               S3      
317P12V             VIA   -     D0100PA00X+026550Y+172214               S3      
317P12V             VIA   -     D0100PA00X+025446Y+172214               S3      
317GND              VIA   -     D0100PA00X+024571Y+171538               S3      
317GND              VIA   -     D0100PA00X+024571Y+170786               S3      
317GND              VIA   -     D0100PA00X+024571Y+169983               S3      
317P12V             J17   -P24  D0300PA00X+025339Y+177189               S0      
317P12V             J17   -P23  D0300PA00X+026339Y+177189               S0      
317P12V             J17   -P9   D0300PA00X+025339Y+178252               S0      
317P12V             J17   -P10  D0300PA00X+026339Y+178252               S0      
317P12V             VIA   -     D0100PA00X+026164Y+181907               S3      
317P12V             VIA   -     D0100PA00X+026164Y+181212               S3      
317P12V             VIA   -     D0100PA00X+026164Y+180520               S3      
317P12V             VIA   -     D0100PA00X+025347Y+181907               S3      
317P12V             VIA   -     D0100PA00X+025347Y+181212               S3      
317P12V             VIA   -     D0100PA00X+025347Y+180520               S3      
317P12V             VIA   -     D0100PA00X+026740Y+181212               S3      
317P12V             VIA   -     D0100PA00X+026740Y+180521               S3      
317P12V             VIA   -     D0100PA00X+026740Y+181908               S3      
317P12V             VIA   -     D0100PA00X+025047Y+180520               S3      
317P12V             VIA   -     D0100PA00X+025047Y+181212               S3      
317P12V             VIA   -     D0100PA00X+025047Y+181907               S3      
317P12V             VIA   -     D0100PA00X+025864Y+180520               S3      
317P12V             VIA   -     D0100PA00X+025864Y+181212               S3      
317P12V             VIA   -     D0100PA00X+025864Y+181907               S3      
317P12V             VIA   -     D0100PA00X+026146Y+182622               S3      
317P12V             VIA   -     D0100PA00X+025329Y+182622               S3      
317P12V             VIA   -     D0100PA00X+026146Y+184009               S3      
317P12V             VIA   -     D0100PA00X+026146Y+183314               S3      
317P12V             VIA   -     D0100PA00X+025329Y+183314               S3      
317P12V             VIA   -     D0100PA00X+025329Y+184009               S3      
317P12V             VIA   -     D0100PA00X+025029Y+184009               S3      
317P12V             VIA   -     D0100PA00X+025029Y+183314               S3      
317P12V             VIA   -     D0100PA00X+026704Y+184009               S3      
317P12V             VIA   -     D0100PA00X+026704Y+183314               S3      
317P12V             VIA   -     D0100PA00X+025846Y+183314               S3      
317P12V             VIA   -     D0100PA00X+025846Y+184009               S3      
317P12V             VIA   -     D0100PA00X+026704Y+182622               S3      
317P12V             VIA   -     D0100PA00X+025029Y+182622               S3      
317P12V             VIA   -     D0100PA00X+025846Y+182622               S3      
317P12V             J18   -P24  D0300PA00X+025339Y+194689               S0      
317P12V             J18   -P9   D0300PA00X+025339Y+195752               S0      
317P12V             J18   -P23  D0300PA00X+026339Y+194689               S0      
317P12V             J18   -P10  D0300PA00X+026339Y+195752               S0      
317P12V             VIA   -     D0100PA00X+024758Y+203148               S3      
317P12V             VIA   -     D0100PA00X+024758Y+202097               S3      
317P12V             VIA   -     D0100PA00X+026034Y+202097               S3      
317P12V             VIA   -     D0100PA00X+026034Y+203148               S3      
317P12V             VIA   -     D0100PA00X+026712Y+202097               S3      
317P12V             VIA   -     D0100PA00X+026712Y+203148               S3      
317P12V             VIA   -     D0100PA00X+025534Y+203148               S3      
317P12V             VIA   -     D0100PA00X+025534Y+202097               S3      
317P12V             VIA   -     D0100PA00X+024758Y+204199               S3      
317P12V             VIA   -     D0100PA00X+024758Y+205132               S3      
317P12V             VIA   -     D0100PA00X+024758Y+205905               S3      
317P12V             VIA   -     D0100PA00X+026034Y+205132               S3      
317P12V             VIA   -     D0100PA00X+026034Y+205905               S3      
317P12V             VIA   -     D0100PA00X+026034Y+204199               S3      
317P12V             VIA   -     D0100PA00X+026712Y+204199               S3      
317P12V             VIA   -     D0100PA00X+026712Y+205905               S3      
317P12V             VIA   -     D0100PA00X+026712Y+205132               S3      
317P12V             VIA   -     D0100PA00X+025534Y+204199               S3      
317P12V             VIA   -     D0100PA00X+025534Y+205905               S3      
317P12V             VIA   -     D0100PA00X+025534Y+205132               S3      
317P12V             VIA   -     D0100PA00X+026034Y+206749               S3      
317P12V             VIA   -     D0100PA00X+024758Y+206749               S3      
317P12V             VIA   -     D0100PA00X+026712Y+206749               S3      
317P12V             VIA   -     D0100PA00X+025534Y+206749               S3      
317GND              VIA   -     D0100PA00X+025999Y+208361               S3      
317GND              VIA   -     D0100PA00X+027522Y+000300               S3      
317P12V             J7    -P22  D0300PA00X+027339Y+002189               S0      
317P12V             J7    -P11  D0300PA00X+027339Y+003252               S0      
317P12V             J7    -P21  D0300PA00X+028339Y+002189               S0      
317P12V             J7    -P12  D0300PA00X+028339Y+003252               S0      
317P12V             VIA   -     D0100PA00X+028810Y+005494               S3      
317P12V             VIA   -     D0100PA00X+028810Y+004557               S3      
317P12V             VIA   -     D0100PA00X+027157Y+005494               S3      
317P12V             VIA   -     D0100PA00X+027975Y+005494               S3      
317P12V             VIA   -     D0100PA00X+027157Y+004557               S3      
317P12V             VIA   -     D0100PA00X+027975Y+004557               S3      
317P12V             VIA   -     D0100PA00X+027975Y+004857               S3      
317P12V             VIA   -     D0100PA00X+027157Y+004857               S3      
317P12V             VIA   -     D0100PA00X+028810Y+004857               S3      
317P12V             VIA   -     D0100PA00X+028810Y+006545               S3      
317P12V             VIA   -     D0100PA00X+027157Y+006545               S3      
317P12V             VIA   -     D0100PA00X+027975Y+006545               S3      
317P12V             VIA   -     D0100PA00X+027975Y+005794               S3      
317P12V             VIA   -     D0100PA00X+027157Y+005794               S3      
317P12V             VIA   -     D0100PA00X+028810Y+005794               S3      
317P12V             VIA   -     D0100PA00X+027975Y+006845               S3      
317P12V             VIA   -     D0100PA00X+027157Y+006845               S3      
317P12V             VIA   -     D0100PA00X+028810Y+006845               S3      
327GND              C12   -2          A01X+027194Y+015126X0180Y0200R090 S2      
327GND              C11   -2          A01X+027652Y+015126X0180Y0200R090 S2      
317GND              VIA   -     D0100PA00X+027652Y+014759               S3      
317GND              VIA   -     D0100PA00X+027194Y+014763               S1      
327P12V             C12   -1          A01X+027194Y+015441X0180Y0200R090 S2      
327P12V             C11   -1          A01X+027652Y+015441X0180Y0200R090 S2      
317P12V             J8    -P22  D0300PA00X+027339Y+019689               S0      
317P12V             J8    -P21  D0300PA00X+028339Y+019689               S0      
317P12V             J8    -P11  D0300PA00X+027339Y+020752               S0      
317P12V             J8    -P12  D0300PA00X+028339Y+020752               S0      
327GND              C9    -2          A01X+027662Y+025344X0180Y0200R270 S2      
327P12V             C9    -1          A01X+027662Y+025029X0180Y0200R270 S2      
327GND              C10   -2          A01X+028119Y+025344X0180Y0200R270 S2      
327P12V             C10   -1          A01X+028119Y+025029X0180Y0200R270 S2      
327P12V             C8    -1          A01X+027155Y+025096X0280Y0320     S2      
327GND              C8    -2          A01X+027155Y+025676X0280Y0320     S2      
317GND              VIA   -     D0100PA00X+027155Y+026035               S1      
317GND              VIA   -     D0100PA00X+027662Y+025640               S3      
317GND              VIA   -     D0100PA00X+028119Y+025662               S1      
317GND              VIA   -     D0100PA00X+028551Y+032269               S3      
317GND              VIA   -     D0100PA00X+028107Y+032269               S1      
317GND              VIA   -     D0100PA00X+028990Y+032269               S1      
327GND              C21   -2          A01X+028107Y+032652X0180Y0200R090 S2      
327P12V             C21   -1          A01X+028107Y+032967X0180Y0200R090 S2      
327GND              C19   -2          A01X+028990Y+032652X0180Y0200R090 S2      
327P12V             C19   -1          A01X+028990Y+032967X0180Y0200R090 S2      
327GND              C20   -2          A01X+028551Y+032652X0180Y0200R090 S2      
327P12V             C20   -1          A01X+028551Y+032967X0180Y0200R090 S2      
317P12V             J9    -P22  D0300PA00X+027339Y+037189               S0      
317P12V             J9    -P21  D0300PA00X+028339Y+037189               S0      
317P12V             J9    -P11  D0300PA00X+027339Y+038252               S0      
317P12V             J9    -P12  D0300PA00X+028339Y+038252               S0      
317P12V             VIA   -     D0100PA00X+027453Y+040729               S3      
317P12V             VIA   -     D0100PA00X+027453Y+039677               S3      
317P12V             VIA   -     D0100PA00X+027453Y+041779               S3      
317P12V             VIA   -     D0100PA00X+027453Y+039977               S3      
317P12V             VIA   -     D0100PA00X+027453Y+041029               S3      
327GND              C17   -2          A01X+029100Y+042902X0180Y0200R270 S2      
327P12V             C17   -1          A01X+029100Y+042587X0180Y0200R270 S2      
327GND              C16   -2          A01X+028667Y+042902X0180Y0200R270 S2      
327P12V             C16   -1          A01X+028667Y+042587X0180Y0200R270 S2      
327P12V             C15   -1          A01X+028157Y+042654X0280Y0320     S2      
327GND              C15   -2          A01X+028157Y+043234X0280Y0320     S2      
317P12V             VIA   -     D0100PA00X+027453Y+042079               S3      
317GND              VIA   -     D0100PA00X+028157Y+043617               S1      
317GND              VIA   -     D0100PA00X+028667Y+043284               S3      
317GND              VIA   -     D0100PA00X+029100Y+043284               S1      
327GND              R116  -2          A01X+027211Y+046310X0180Y0200R180 S2      
327NNAME10032       R116  -1          A01X+026896Y+046310X0180Y0200R180 S2      
317GND              VIA   -     D0100PA00X+027499Y+046310               S3      
327P12V             R115  -2          A01X+027204Y+047368X0180Y0200R180 S2      
327NNAME10043       R115  -1          A01X+026889Y+047368X0180Y0200R180 S2      
327GND              C26   -2          A01X+027341Y+050092X0180Y0200R090 S2      
327P12V             C26   -1          A01X+027341Y+050407X0180Y0200R090 S2      
327GND              C27   -2          A01X+026894Y+050092X0180Y0200R090 S2      
327P12V             C27   -1          A01X+026894Y+050407X0180Y0200R090 S2      
327GND              C25   -2          A01X+027778Y+050092X0180Y0200R090 S2      
327P12V             C25   -1          A01X+027778Y+050407X0180Y0200R090 S2      
317GND              VIA   -     D0100PA00X+027778Y+049734               S3      
317GND              VIA   -     D0100PA00X+027341Y+049734               S1      
317GND              VIA   -     D0100PA00X+026894Y+049734               S3      
317P12V             VIA   -     D0100PA00X+028957Y+053276               S3      
317P12V             VIA   -     D0100PA00X+028957Y+051660               S3      
317P12V             VIA   -     D0100PA00X+028957Y+052432               S3      
317P12V             J10   -P22  D0300PA00X+027339Y+054689               S0      
317P12V             J10   -P11  D0300PA00X+027339Y+055752               S0      
317P12V             J10   -P21  D0300PA00X+028339Y+054689               S0      
317P12V             J10   -P12  D0300PA00X+028339Y+055752               S0      
317P12V             VIA   -     D0100PA00X+027894Y+058144               S3      
317P12V             VIA   -     D0100PA00X+027894Y+057264               S3      
317P12V             VIA   -     D0100PA00X+027594Y+057264               S3      
317P12V             VIA   -     D0100PA00X+027594Y+058144               S3      
327GND              C23   -2          A01X+029098Y+060364X0180Y0200R270 S2      
327P12V             C23   -1          A01X+029098Y+060049X0180Y0200R270 S2      
327P12V             C22   -1          A01X+028535Y+060116X0280Y0320     S2      
327GND              C22   -2          A01X+028535Y+060696X0280Y0320     S2      
317P12V             VIA   -     D0100PA00X+027894Y+060128               S3      
317P12V             VIA   -     D0100PA00X+027894Y+060901               S3      
317P12V             VIA   -     D0100PA00X+027894Y+059195               S3      
317P12V             VIA   -     D0100PA00X+027594Y+059195               S3      
317P12V             VIA   -     D0100PA00X+027594Y+060901               S3      
317P12V             VIA   -     D0100PA00X+027594Y+060128               S3      
317GND              VIA   -     D0100PA00X+028535Y+061054               S1      
317GND              VIA   -     D0100PA00X+029098Y+060722               S3      
317P12V             VIA   -     D0100PA00X+027894Y+061745               S3      
317P12V             VIA   -     D0100PA00X+027594Y+061745               S3      
317GND              VIA   -     D0100PA00X+027604Y+062463               S3      
317GND              VIA   -     D0100PA00X+027904Y+062463               S3      
327GND              C32   -2          A01X+028334Y+067612X0180Y0200R090 S2      
327P12V             C32   -1          A01X+028334Y+067927X0180Y0200R090 S2      
327GND              C33   -2          A01X+027896Y+067612X0180Y0200R090 S2      
327P12V             C33   -1          A01X+027896Y+067927X0180Y0200R090 S2      
327GND              C34   -2          A01X+027451Y+067612X0180Y0200R090 S2      
327P12V             C34   -1          A01X+027451Y+067927X0180Y0200R090 S2      
327GND              C35   -2          A01X+027011Y+067612X0180Y0200R090 S2      
327P12V             C35   -1          A01X+027011Y+067927X0180Y0200R090 S2      
317GND              VIA   -     D0100PA00X+027451Y+067219               S3      
317GND              VIA   -     D0100PA00X+027011Y+067219               S1      
317GND              VIA   -     D0100PA00X+028334Y+067219               S3      
317GND              VIA   -     D0100PA00X+027896Y+067219               S1      
317P12V             J11   -P22  D0300PA00X+027339Y+072189               S0      
317P12V             J11   -P11  D0300PA00X+027339Y+073252               S0      
317P12V             J11   -P21  D0300PA00X+028339Y+072189               S0      
317P12V             J11   -P12  D0300PA00X+028339Y+073252               S0      
327GND              C30   -2          A01X+027818Y+077871X0180Y0200R270 S2      
327P12V             C30   -1          A01X+027818Y+077556X0180Y0200R270 S2      
327GND              C31   -2          A01X+028274Y+077871X0180Y0200R270 S2      
327P12V             C31   -1          A01X+028274Y+077556X0180Y0200R270 S2      
327P12V             C29   -1          A01X+027311Y+077624X0280Y0320     S2      
327GND              C29   -2          A01X+027311Y+078204X0280Y0320     S2      
317GND              VIA   -     D0100PA00X+027311Y+078597               S1      
317GND              VIA   -     D0100PA00X+027818Y+078264               S3      
317GND              VIA   -     D0100PA00X+028274Y+078264               S1      
317GND              VIA   -     D0100PA00X+027007Y+081219               S3      
327GND              C39   -2          A01X+027779Y+085124X0180Y0200R090 S2      
327GND              C40   -2          A01X+027331Y+085124X0180Y0200R090 S2      
327GND              C41   -2          A01X+026869Y+085124X0180Y0200R090 S2      
317GND              VIA   -     D0100PA00X+026869Y+084749               S3      
317GND              VIA   -     D0100PA00X+027779Y+084724               S3      
317GND              VIA   -     D0100PA00X+027331Y+084724               S1      
327P12V             C39   -1          A01X+027779Y+085439X0180Y0200R090 S2      
327P12V             C40   -1          A01X+027331Y+085439X0180Y0200R090 S2      
327P12V             C41   -1          A01X+026869Y+085439X0180Y0200R090 S2      
317P12V             J12   -P22  D0300PA00X+027339Y+089689               S0      
317P12V             J12   -P21  D0300PA00X+028339Y+089689               S0      
317P12V             J12   -P11  D0300PA00X+027339Y+090752               S0      
317P12V             J12   -P12  D0300PA00X+028339Y+090752               S0      
327P12V             C37   -1          A01X+029119Y+094929X0180Y0200R270 S2      
327P12V             C36   -1          A01X+028597Y+094996X0280Y0320     S2      
317P12V             VIA   -     D0100PA00X+027754Y+094934               S3      
317P12V             VIA   -     D0100PA00X+027454Y+094934               S3      
327GND              C37   -2          A01X+029119Y+095244X0180Y0200R270 S2      
327GND              C36   -2          A01X+028597Y+095576X0280Y0320     S2      
317P12V             VIA   -     D0100PA00X+027754Y+096711               S3      
317P12V             VIA   -     D0100PA00X+027754Y+095986               S3      
317P12V             VIA   -     D0100PA00X+027740Y+097439               S3      
317P12V             VIA   -     D0100PA00X+027440Y+097439               S3      
317P12V             VIA   -     D0100PA00X+027454Y+095986               S3      
317P12V             VIA   -     D0100PA00X+027454Y+096711               S3      
317GND              VIA   -     D0100PA00X+028597Y+095977               S1      
317GND              VIA   -     D0100PA00X+029119Y+095644               S3      
317P12V             VIA   -     D0100PA00X+027740Y+099055               S3      
317P12V             VIA   -     D0100PA00X+027740Y+098211               S3      
317P12V             VIA   -     D0100PA00X+027440Y+098211               S3      
317P12V             VIA   -     D0100PA00X+027440Y+099055               S3      
327GND              C47   -2          A01X+029011Y+101988X0180Y0200R090 S2      
327GND              C48   -2          A01X+028567Y+101988X0180Y0200R090 S2      
327GND              C49   -2          A01X+028112Y+101988X0180Y0200R090 S2      
317GND              VIA   -     D0100PA00X+028567Y+101616               S3      
317GND              VIA   -     D0100PA00X+028112Y+101616               S1      
317GND              VIA   -     D0100PA00X+029011Y+101616               S1      
327P12V             C47   -1          A01X+029011Y+102303X0180Y0200R090 S2      
327P12V             C48   -1          A01X+028567Y+102303X0180Y0200R090 S2      
327P12V             C49   -1          A01X+028112Y+102303X0180Y0200R090 S2      
317P12V             J13   -P22  D0300PA00X+027339Y+107189               S0      
317P12V             J13   -P21  D0300PA00X+028339Y+107189               S0      
317P12V             J13   -P11  D0300PA00X+027339Y+108252               S0      
317P12V             J13   -P12  D0300PA00X+028339Y+108252               S0      
327GND              C44   -2          A01X+028819Y+112743X0180Y0200R270 S2      
327P12V             C44   -1          A01X+028819Y+112428X0180Y0200R270 S2      
327P12V             C43   -1          A01X+028296Y+112495X0280Y0320     S2      
327GND              C43   -2          A01X+028296Y+113075X0280Y0320     S2      
317P12V             VIA   -     D0100PA00X+027282Y+112447               S3      
317P12V             VIA   -     D0100PA00X+027282Y+113499               S3      
317P12V             VIA   -     D0100PA00X+026982Y+113499               S3      
317P12V             VIA   -     D0100PA00X+026982Y+112447               S3      
317GND              VIA   -     D0100PA00X+028296Y+113447               S1      
317GND              VIA   -     D0100PA00X+028819Y+113115               S3      
317P12V             VIA   -     D0100PA00X+027282Y+114549               S3      
317P12V             VIA   -     D0100PA00X+026982Y+114549               S3      
317P12V             VIA   -     D0100PA00X+028418Y+118446               S3      
317P12V             VIA   -     D0100PA00X+028418Y+119218               S3      
317P12V             VIA   -     D0100PA00X+028718Y+119218               S3      
317P12V             VIA   -     D0100PA00X+028718Y+118446               S3      
317GND              VIA   -     D0100PA00X+027681Y+119178               S3      
317GND              VIA   -     D0100PA00X+027208Y+119178               S1      
327GND              C53   -2          A01X+027681Y+119531X0180Y0200R090 S2      
327P12V             C53   -1          A01X+027681Y+119846X0180Y0200R090 S2      
327GND              C54   -2          A01X+027208Y+119531X0180Y0200R090 S2      
327P12V             C54   -1          A01X+027208Y+119846X0180Y0200R090 S2      
317P12V             VIA   -     D0100PA00X+028418Y+120062               S3      
317P12V             VIA   -     D0100PA00X+028718Y+120062               S3      
317P12V             J14   -P22  D0300PA00X+027339Y+124689               S0      
317P12V             J14   -P11  D0300PA00X+027339Y+125752               S0      
317P12V             J14   -P21  D0300PA00X+028339Y+124689               S0      
317P12V             J14   -P12  D0300PA00X+028339Y+125752               S0      
317P12V             VIA   -     D0100PA00X+027062Y+128295               S3      
317P12V             VIA   -     D0100PA00X+027062Y+127243               S3      
327GND              C51   -2          A01X+028921Y+130210X0180Y0200R270 S2      
327P12V             C51   -1          A01X+028921Y+129895X0180Y0200R270 S2      
327P12V             C50   -1          A01X+028381Y+129962X0280Y0320     S2      
327GND              C50   -2          A01X+028381Y+130542X0280Y0320     S2      
317P12V             VIA   -     D0100PA00X+027062Y+129345               S3      
317P12V             VIA   -     D0100PA00X+027062Y+130279               S3      
317P12V             VIA   -     D0100PA00X+027062Y+131052               S3      
317GND              VIA   -     D0100PA00X+028381Y+130896               S1      
317GND              VIA   -     D0100PA00X+028921Y+130563               S3      
317P12V             VIA   -     D0100PA00X+027062Y+131895               S3      
327GND              C60   -2          A01X+028424Y+137834X0180Y0200R090 S2      
327P12V             C60   -1          A01X+028424Y+138149X0180Y0200R090 S2      
327GND              C61   -2          A01X+027952Y+137834X0180Y0200R090 S2      
327P12V             C61   -1          A01X+027952Y+138149X0180Y0200R090 S2      
327GND              C62   -2          A01X+027505Y+137834X0180Y0200R090 S2      
327P12V             C62   -1          A01X+027505Y+138149X0180Y0200R090 S2      
327GND              C63   -2          A01X+027058Y+137834X0180Y0200R090 S2      
327P12V             C63   -1          A01X+027058Y+138149X0180Y0200R090 S2      
317GND              VIA   -     D0100PA00X+028424Y+137454               S3      
317GND              VIA   -     D0100PA00X+027952Y+137454               S1      
317GND              VIA   -     D0100PA00X+027505Y+137472               S3      
317GND              VIA   -     D0100PA00X+027058Y+137463               S1      
317P12V             J15   -P22  D0300PA00X+027339Y+142189               S0      
317P12V             J15   -P11  D0300PA00X+027339Y+143252               S0      
317P12V             J15   -P21  D0300PA00X+028339Y+142189               S0      
317P12V             J15   -P12  D0300PA00X+028339Y+143252               S0      
327GND              C58   -2          A01X+027552Y+147564X0180Y0200R270 S2      
327P12V             C58   -1          A01X+027552Y+147249X0180Y0200R270 S2      
327GND              C59   -2          A01X+027999Y+147564X0180Y0200R270 S2      
327P12V             C59   -1          A01X+027999Y+147249X0180Y0200R270 S2      
327P12V             C57   -1          A01X+027023Y+147316X0280Y0320     S2      
327GND              C57   -2          A01X+027023Y+147896X0280Y0320     S2      
317GND              VIA   -     D0100PA00X+027552Y+147944               S3      
317GND              VIA   -     D0100PA00X+027999Y+147944               S1      
317GND              VIA   -     D0100PA00X+027023Y+148276               S1      
327GND              C70   -2          A01X+029105Y+154745X0180Y0200R090 S2      
327P12V             C70   -1          A01X+029105Y+155060X0180Y0200R090 S2      
317P12V             VIA   -     D0100PA00X+027540Y+154819               S3      
317P12V             VIA   -     D0100PA00X+026853Y+154801               S3      
317P12V             VIA   -     D0100PA00X+028300Y+154819               S3      
317P12V             VIA   -     D0100PA00X+027540Y+153432               S3      
317P12V             VIA   -     D0100PA00X+027540Y+154124               S3      
317P12V             VIA   -     D0100PA00X+026853Y+153414               S3      
317P12V             VIA   -     D0100PA00X+026853Y+154106               S3      
317P12V             VIA   -     D0100PA00X+028300Y+153432               S3      
317P12V             VIA   -     D0100PA00X+028300Y+154124               S3      
317P12V             VIA   -     D0100PA00X+028600Y+154124               S3      
317P12V             VIA   -     D0100PA00X+028600Y+153432               S3      
317P12V             VIA   -     D0100PA00X+027153Y+154106               S3      
317P12V             VIA   -     D0100PA00X+027153Y+153414               S3      
317P12V             VIA   -     D0100PA00X+027840Y+154124               S3      
317P12V             VIA   -     D0100PA00X+027840Y+153432               S3      
317P12V             VIA   -     D0100PA00X+028600Y+154819               S3      
317P12V             VIA   -     D0100PA00X+027153Y+154801               S3      
317P12V             VIA   -     D0100PA00X+027840Y+154819               S3      
317GND              VIA   -     D0100PA00X+029105Y+154321               S1      
317P12V             J16   -P22  D0300PA00X+027339Y+159689               S0      
317P12V             J16   -P21  D0300PA00X+028339Y+159689               S0      
317P12V             J16   -P11  D0300PA00X+027339Y+160752               S0      
317P12V             J16   -P12  D0300PA00X+028339Y+160752               S0      
317P12V             VIA   -     D0100PA00X+027034Y+162182               S3      
317P12V             VIA   -     D0100PA00X+027334Y+162182               S3      
327P12V             C65   -1          A01X+028942Y+164917X0180Y0200R270 S2      
327P12V             C64   -1          A01X+028409Y+164984X0280Y0320     S2      
317P12V             VIA   -     D0100PA00X+027034Y+164284               S3      
317P12V             VIA   -     D0100PA00X+027034Y+163234               S3      
317P12V             VIA   -     D0100PA00X+027334Y+163234               S3      
317P12V             VIA   -     D0100PA00X+027334Y+164284               S3      
327GND              C65   -2          A01X+028942Y+165232X0180Y0200R270 S2      
327GND              C64   -2          A01X+028409Y+165564X0280Y0320     S2      
317P12V             VIA   -     D0100PA00X+027034Y+166835               S3      
317P12V             VIA   -     D0100PA00X+027034Y+165218               S3      
317P12V             VIA   -     D0100PA00X+027034Y+165991               S3      
317P12V             VIA   -     D0100PA00X+027334Y+165991               S3      
317P12V             VIA   -     D0100PA00X+027334Y+165218               S3      
317P12V             VIA   -     D0100PA00X+027334Y+166835               S3      
317GND              VIA   -     D0100PA00X+028409Y+165988               S1      
317GND              VIA   -     D0100PA00X+028942Y+165656               S3      
317GND              VIA   -     D0100PA00X+027970Y+172340               S3      
317GND              VIA   -     D0100PA00X+028458Y+172347               S1      
317GND              VIA   -     D0100PA00X+028950Y+172374               S3      
317GND              VIA   -     D0100PA00X+027470Y+172320               S1      
327GND              C74   -2          A01X+028950Y+172692X0180Y0200R090 S2      
327P12V             C74   -1          A01X+028950Y+173007X0180Y0200R090 S2      
327GND              C75   -2          A01X+028458Y+172692X0180Y0200R090 S2      
327P12V             C75   -1          A01X+028458Y+173007X0180Y0200R090 S2      
327GND              C77   -2          A01X+027470Y+172692X0180Y0200R090 S2      
327P12V             C77   -1          A01X+027470Y+173007X0180Y0200R090 S2      
327GND              C76   -2          A01X+027970Y+172692X0180Y0200R090 S2      
327P12V             C76   -1          A01X+027970Y+173007X0180Y0200R090 S2      
317P12V             J17   -P22  D0300PA00X+027339Y+177189               S0      
317P12V             J17   -P21  D0300PA00X+028339Y+177189               S0      
317P12V             J17   -P11  D0300PA00X+027339Y+178252               S0      
317P12V             J17   -P12  D0300PA00X+028339Y+178252               S0      
317P12V             VIA   -     D0100PA00X+027040Y+181908               S3      
317P12V             VIA   -     D0100PA00X+027040Y+180521               S3      
317P12V             VIA   -     D0100PA00X+027040Y+181212               S3      
327GND              C72   -2          A01X+028662Y+182655X0180Y0200R270 S2      
327P12V             C72   -1          A01X+028662Y+182340X0180Y0200R270 S2      
327GND              C73   -2          A01X+029155Y+182655X0180Y0200R270 S2      
327P12V             C73   -1          A01X+029155Y+182340X0180Y0200R270 S2      
327P12V             C71   -1          A01X+028107Y+182407X0280Y0320     S2      
327GND              C71   -2          A01X+028107Y+182987X0280Y0320     S2      
317P12V             VIA   -     D0100PA00X+027004Y+182622               S3      
317P12V             VIA   -     D0100PA00X+027004Y+183314               S3      
317P12V             VIA   -     D0100PA00X+027004Y+184009               S3      
317GND              VIA   -     D0100PA00X+028107Y+183457               S1      
317GND              VIA   -     D0100PA00X+029155Y+182985               S1      
317GND              VIA   -     D0100PA00X+028662Y+182940               S3      
327P12V             R131  -2          A01X+028871Y+186457X0180Y0200R180 S2      
327NNAME10048       R131  -1          A01X+028556Y+186457X0180Y0200R180 S2      
327GND              R132  -2          A01X+028879Y+185867X0180Y0200R180 S2      
327NNAME10039       R132  -1          A01X+028564Y+185867X0180Y0200R180 S2      
317NNAME10039       VIA   -     D0100PA00X+028024Y+185867               S1      
317NNAME10048       VIA   -     D0100PA00X+027998Y+186457               S1      
327GND              C81   -2          A01X+028712Y+190190X0180Y0200R090 S2      
327P12V             C81   -1          A01X+028712Y+190505X0180Y0200R090 S2      
327GND              C82   -2          A01X+028272Y+190190X0180Y0200R090 S2      
327P12V             C82   -1          A01X+028272Y+190505X0180Y0200R090 S2      
327GND              C83   -2          A01X+027826Y+190190X0180Y0200R090 S2      
327P12V             C83   -1          A01X+027826Y+190505X0180Y0200R090 S2      
327GND              C84   -2          A01X+027382Y+190190X0180Y0200R090 S2      
327P12V             C84   -1          A01X+027382Y+190505X0180Y0200R090 S2      
317GND              VIA   -     D0100PA00X+028712Y+189833               S3      
317GND              VIA   -     D0100PA00X+028272Y+189833               S1      
317GND              VIA   -     D0100PA00X+027826Y+189833               S3      
317GND              VIA   -     D0100PA00X+027382Y+189833               S1      
317P12V             J18   -P22  D0300PA00X+027339Y+194689               S0      
317P12V             J18   -P11  D0300PA00X+027339Y+195752               S0      
317P12V             J18   -P21  D0300PA00X+028339Y+194689               S0      
317P12V             J18   -P12  D0300PA00X+028339Y+195752               S0      
317P12V             VIA   -     D0100PA00X+027212Y+203148               S3      
317P12V             VIA   -     D0100PA00X+027212Y+202097               S3      
317P12V             VIA   -     D0100PA00X+027212Y+205132               S3      
317P12V             VIA   -     D0100PA00X+027212Y+205905               S3      
317P12V             VIA   -     D0100PA00X+027212Y+204199               S3      
317P12V             VIA   -     D0100PA00X+027212Y+206749               S3      
317P12V             J7    -P20  D0300PA00X+029339Y+002189               S0      
317P12V             J7    -P13  D0300PA00X+029339Y+003252               S0      
317P12V             J7    -P19  D0300PA00X+030339Y+002189               S0      
317P12V             J7    -P14  D0300PA00X+030339Y+003252               S0      
317P12V             J7    -P15  D0300PA00X+031339Y+003252               S0      
317P12V             J7    -P18  D0300PA00X+031339Y+002189               S0      
327GND              C3    -2          A01X+030415Y+007539X0180Y0200R270 S2      
327P12V             C3    -1          A01X+030415Y+007224X0180Y0200R270 S2      
327GND              C4    -2          A01X+030865Y+007539X0180Y0200R270 S2      
327P12V             C4    -1          A01X+030865Y+007224X0180Y0200R270 S2      
327GND              C5    -2          A01X+031309Y+007539X0180Y0200R270 S2      
327P12V             C5    -1          A01X+031309Y+007224X0180Y0200R270 S2      
327GND              C2    -2          A01X+029969Y+007539X0180Y0200R270 S2      
327P12V             C2    -1          A01X+029969Y+007224X0180Y0200R270 S2      
327P12V             C1    -1          A01X+029448Y+007292X0280Y0320     S2      
327GND              C1    -2          A01X+029448Y+007872X0280Y0320     S2      
317GND              VIA   -     D0100PA00X+029969Y+007878               S3      
317GND              VIA   -     D0100PA00X+030415Y+007878               S1      
317GND              VIA   -     D0100PA00X+030865Y+007878               S3      
317GND              VIA   -     D0100PA00X+031309Y+007878               S1      
317GND              VIA   -     D0100PA00X+029448Y+008273               S1      
317GND              H12   -6    D0220PA00X+030709Y+011339               S0      
317GND              H12   -5    D0220PA00X+029724Y+011732               S0      
317GND              H12   -4    D0220PA00X+029331Y+012717               S0      
317N/C              H12   -1    D1580UA00X+030709Y+012717               S0      
317GND              H12   -3    D0220PA00X+029724Y+013701               S0      
317GND              H12   -2    D0220PA00X+030709Y+014095               S0      
317P12V             J8    -P20  D0300PA00X+029339Y+019689               S0      
317P12V             J8    -P19  D0300PA00X+030339Y+019689               S0      
317P12V             J8    -P18  D0300PA00X+031339Y+019689               S0      
317P12V             J8    -P13  D0300PA00X+029339Y+020752               S0      
317P12V             J8    -P14  D0300PA00X+030339Y+020752               S0      
317P12V             J8    -P15  D0300PA00X+031339Y+020752               S0      
317T2_BLAD1_RXD     VIA   -     D0100PA00X+030806Y+024886               S1      
317T2_BLAD1_TXD     VIA   -     D0100PA00X+030627Y+024101               S1      
317T2_BLAD3_TXD     VIA   -     D0100PA00X+031491Y+023816               S1      
317T2_BLAD1_EN      VIA   -     D0100PA00X+031494Y+025208               S1      
317N/C              H14   -1    D2050UA00X+030709Y+030827               S0      
317GND              VIA   -     D0100PA00X+029451Y+032269               S3      
327GND              C18   -2          A01X+029451Y+032652X0180Y0200R090 S2      
327P12V             C18   -1          A01X+029451Y+032967X0180Y0200R090 S2      
317P12V             J9    -P20  D0300PA00X+029339Y+037189               S0      
317P12V             J9    -P19  D0300PA00X+030339Y+037189               S0      
317P12V             J9    -P18  D0300PA00X+031339Y+037189               S0      
317P12V             J9    -P13  D0300PA00X+029339Y+038252               S0      
317P12V             J9    -P14  D0300PA00X+030339Y+038252               S0      
317P12V             J9    -P15  D0300PA00X+031339Y+038252               S0      
317GND              H9    -6    D0220PA00X+030709Y+046339               S0      
317GND              H9    -5    D0220PA00X+029724Y+046732               S0      
317GND              H9    -4    D0220PA00X+029331Y+047717               S0      
317GND              H9    -3    D0220PA00X+029724Y+048701               S0      
317GND              H9    -2    D0220PA00X+030709Y+049095               S0      
317N/C              H9    -1    D1580UA00X+030709Y+047717               S0      
317P12V             VIA   -     D0100PA00X+030054Y+051631               S3      
317P12V             VIA   -     D0100PA00X+030797Y+051642               S3      
317P12V             VIA   -     D0100PA00X+030797Y+052415               S3      
317P12V             VIA   -     D0100PA00X+030054Y+052404               S3      
317P12V             VIA   -     D0100PA00X+030054Y+053248               S3      
317P12V             VIA   -     D0100PA00X+030797Y+053259               S3      
317P12V             VIA   -     D0100PA00X+029257Y+052432               S3      
317P12V             VIA   -     D0100PA00X+029257Y+051660               S3      
317P12V             VIA   -     D0100PA00X+029257Y+053276               S3      
317P12V             VIA   -     D0100PA00X+030497Y+053259               S3      
317P12V             VIA   -     D0100PA00X+029754Y+053248               S3      
317P12V             VIA   -     D0100PA00X+029754Y+052404               S3      
317P12V             VIA   -     D0100PA00X+030497Y+052415               S3      
317P12V             VIA   -     D0100PA00X+030497Y+051642               S3      
317P12V             VIA   -     D0100PA00X+029754Y+051631               S3      
317P12V             VIA   -     D0100PA00X+031379Y+053287               S3      
317P12V             VIA   -     D0100PA00X+031379Y+051670               S3      
317P12V             VIA   -     D0100PA00X+031379Y+052443               S3      
317P12V             J10   -P20  D0300PA00X+029339Y+054689               S0      
317P12V             J10   -P13  D0300PA00X+029339Y+055752               S0      
317P12V             J10   -P19  D0300PA00X+030339Y+054689               S0      
317P12V             J10   -P14  D0300PA00X+030339Y+055752               S0      
317P12V             J10   -P15  D0300PA00X+031339Y+055752               S0      
317P12V             J10   -P18  D0300PA00X+031339Y+054689               S0      
327GND              C24   -2          A01X+029551Y+060364X0180Y0200R270 S2      
327P12V             C24   -1          A01X+029551Y+060049X0180Y0200R270 S2      
317GND              VIA   -     D0100PA00X+029551Y+060722               S1      
317P12V             VIA   -     D0100PA00X+031519Y+065246               S3      
317P12V             VIA   -     D0100PA00X+030415Y+065246               S3      
317P12V             VIA   -     D0100PA00X+030715Y+065246               S3      
317P12V             VIA   -     D0100PA00X+031519Y+066126               S3      
317P12V             VIA   -     D0100PA00X+030415Y+066126               S3      
317P12V             VIA   -     D0100PA00X+030415Y+068110               S3      
317P12V             VIA   -     D0100PA00X+031519Y+068110               S3      
317P12V             VIA   -     D0100PA00X+031519Y+067176               S3      
317P12V             VIA   -     D0100PA00X+030415Y+067176               S3      
317P12V             VIA   -     D0100PA00X+030715Y+067176               S3      
317P12V             VIA   -     D0100PA00X+030715Y+068110               S3      
317P12V             VIA   -     D0100PA00X+030715Y+066126               S3      
317P12V             VIA   -     D0100PA00X+031519Y+068883               S3      
317P12V             VIA   -     D0100PA00X+030415Y+068883               S3      
317P12V             VIA   -     D0100PA00X+030415Y+069727               S3      
317P12V             VIA   -     D0100PA00X+031519Y+069727               S3      
317P12V             VIA   -     D0100PA00X+030715Y+069727               S3      
317P12V             VIA   -     D0100PA00X+030715Y+068883               S3      
317P12V             J11   -P20  D0300PA00X+029339Y+072189               S0      
317P12V             J11   -P13  D0300PA00X+029339Y+073252               S0      
317P12V             J11   -P19  D0300PA00X+030339Y+072189               S0      
317P12V             J11   -P14  D0300PA00X+030339Y+073252               S0      
317P12V             J11   -P15  D0300PA00X+031339Y+073252               S0      
317P12V             J11   -P18  D0300PA00X+031339Y+072189               S0      
317GND              H7    -6    D0220PA00X+030709Y+081339               S0      
317GND              H7    -5    D0220PA00X+029724Y+081732               S0      
317GND              H7    -4    D0220PA00X+029331Y+082717               S0      
317N/C              H7    -1    D1580UA00X+030709Y+082717               S0      
317GND              H7    -3    D0220PA00X+029724Y+083701               S0      
317GND              H7    -2    D0220PA00X+030709Y+084095               S0      
317P12V             J12   -P20  D0300PA00X+029339Y+089689               S0      
317P12V             J12   -P19  D0300PA00X+030339Y+089689               S0      
317P12V             J12   -P18  D0300PA00X+031339Y+089689               S0      
317P12V             J12   -P13  D0300PA00X+029339Y+090752               S0      
317P12V             J12   -P14  D0300PA00X+030339Y+090752               S0      
317P12V             J12   -P15  D0300PA00X+031339Y+090752               S0      
327P12V             C38   -1          A01X+029587Y+094929X0180Y0200R270 S2      
327GND              C38   -2          A01X+029587Y+095244X0180Y0200R270 S2      
317GND              VIA   -     D0100PA00X+029587Y+095644               S1      
327GND              C46   -2          A01X+029462Y+101988X0180Y0200R090 S2      
317P12V             VIA   -     D0100PA00X+031019Y+102066               S3      
317P12V             VIA   -     D0100PA00X+031008Y+100730               S3      
317P12V             VIA   -     D0100PA00X+031027Y+100129               S3      
317P12V             VIA   -     D0100PA00X+031014Y+101409               S3      
317P12V             VIA   -     D0100PA00X+030714Y+101409               S3      
317P12V             VIA   -     D0100PA00X+030727Y+100129               S3      
317P12V             VIA   -     D0100PA00X+030708Y+100730               S3      
317P12V             VIA   -     D0100PA00X+030719Y+102066               S3      
317GND              VIA   -     D0100PA00X+029462Y+101616               S3      
327P12V             C46   -1          A01X+029462Y+102303X0180Y0200R090 S2      
317P12V             VIA   -     D0100PA00X+031013Y+102708               S3      
317P12V             VIA   -     D0100PA00X+031000Y+103372               S3      
317P12V             VIA   -     D0100PA00X+030700Y+103372               S3      
317P12V             VIA   -     D0100PA00X+030713Y+102708               S3      
317P12V             J13   -P20  D0300PA00X+029339Y+107189               S0      
317P12V             J13   -P19  D0300PA00X+030339Y+107189               S0      
317P12V             J13   -P18  D0300PA00X+031339Y+107189               S0      
317T7_BLAD2_TXD     VIA   -     D0100PA00X+030968Y+105326               S1      
317P12V             J13   -P13  D0300PA00X+029339Y+108252               S0      
317P12V             J13   -P14  D0300PA00X+030339Y+108252               S0      
317P12V             J13   -P15  D0300PA00X+031339Y+108252               S0      
327GND              C45   -2          A01X+029270Y+112743X0180Y0200R270 S2      
327P12V             C45   -1          A01X+029270Y+112428X0180Y0200R270 S2      
317GND              VIA   -     D0100PA00X+029270Y+113115               S1      
317NNAME10036       VIA   -     D0100PA00X+031253Y+116227               S1      
317P12V             VIA   -     D0100PA00X+030916Y+118453               S3      
317P12V             VIA   -     D0100PA00X+030916Y+119225               S3      
317P12V             VIA   -     D0100PA00X+030069Y+118453               S3      
317P12V             VIA   -     D0100PA00X+029272Y+118431               S3      
317P12V             VIA   -     D0100PA00X+029272Y+119204               S3      
317P12V             VIA   -     D0100PA00X+030069Y+119225               S3      
317P12V             VIA   -     D0100PA00X+030369Y+119225               S3      
317P12V             VIA   -     D0100PA00X+029572Y+119204               S3      
317P12V             VIA   -     D0100PA00X+029572Y+118431               S3      
317P12V             VIA   -     D0100PA00X+030369Y+118453               S3      
317P12V             VIA   -     D0100PA00X+031216Y+119225               S3      
317P12V             VIA   -     D0100PA00X+031216Y+118453               S3      
317NNAME10045       VIA   -     D0100PA00X+031270Y+117280               S1      
317P12V             VIA   -     D0100PA00X+030916Y+120069               S3      
317P12V             VIA   -     D0100PA00X+030069Y+120069               S3      
317P12V             VIA   -     D0100PA00X+029272Y+120048               S3      
317P12V             VIA   -     D0100PA00X+029572Y+120048               S3      
317P12V             VIA   -     D0100PA00X+030369Y+120069               S3      
317P12V             VIA   -     D0100PA00X+031216Y+120069               S3      
317P12V             J14   -P20  D0300PA00X+029339Y+124689               S0      
317P12V             J14   -P13  D0300PA00X+029339Y+125752               S0      
317P12V             J14   -P19  D0300PA00X+030339Y+124689               S0      
317P12V             J14   -P14  D0300PA00X+030339Y+125752               S0      
317P12V             J14   -P15  D0300PA00X+031339Y+125752               S0      
317P12V             J14   -P18  D0300PA00X+031339Y+124689               S0      
327GND              C52   -2          A01X+029413Y+130210X0180Y0200R270 S2      
327P12V             C52   -1          A01X+029413Y+129895X0180Y0200R270 S2      
317GND              VIA   -     D0100PA00X+029413Y+130563               S1      
317GND              H5    -6    D0220PA00X+030709Y+132972               S0      
317GND              H5    -5    D0220PA00X+029724Y+133366               S0      
317N/C              H5    -1    D1580UA00X+030709Y+134350               S0      
317GND              H5    -4    D0220PA00X+029331Y+134350               S0      
317GND              H5    -3    D0220PA00X+029724Y+135335               S0      
317GND              H5    -2    D0220PA00X+030709Y+135728               S0      
317T9_BLAD3_EN      VIA   -     D0100PA00X+031418Y+140342               S1      
317P12V             J15   -P20  D0300PA00X+029339Y+142189               S0      
317P12V             J15   -P13  D0300PA00X+029339Y+143252               S0      
317P12V             J15   -P19  D0300PA00X+030339Y+142189               S0      
317P12V             J15   -P14  D0300PA00X+030339Y+143252               S0      
317P12V             J15   -P15  D0300PA00X+031339Y+143252               S0      
317P12V             J15   -P18  D0300PA00X+031339Y+142189               S0      
317P12V             VIA   -     D0100PA00X+031282Y+147296               S3      
317P12V             VIA   -     D0100PA00X+031246Y+148010               S3      
317P12V             VIA   -     D0100PA00X+031282Y+146600               S3      
317P12V             VIA   -     D0100PA00X+031282Y+145909               S3      
317P12V             VIA   -     D0100PA00X+029572Y+148010               S3      
317P12V             VIA   -     D0100PA00X+029590Y+147295               S3      
317P12V             VIA   -     D0100PA00X+030407Y+147295               S3      
317P12V             VIA   -     D0100PA00X+030389Y+148010               S3      
317P12V             VIA   -     D0100PA00X+029590Y+145908               S3      
317P12V             VIA   -     D0100PA00X+029590Y+146600               S3      
317P12V             VIA   -     D0100PA00X+030407Y+146600               S3      
317P12V             VIA   -     D0100PA00X+030407Y+145908               S3      
317P12V             VIA   -     D0100PA00X+030107Y+145908               S3      
317P12V             VIA   -     D0100PA00X+030107Y+146600               S3      
317P12V             VIA   -     D0100PA00X+029290Y+146600               S3      
317P12V             VIA   -     D0100PA00X+029290Y+145908               S3      
317P12V             VIA   -     D0100PA00X+030089Y+148010               S3      
317P12V             VIA   -     D0100PA00X+030107Y+147295               S3      
317P12V             VIA   -     D0100PA00X+029290Y+147295               S3      
317P12V             VIA   -     D0100PA00X+029272Y+148010               S3      
317P12V             VIA   -     D0100PA00X+030982Y+145909               S3      
317P12V             VIA   -     D0100PA00X+030982Y+146600               S3      
317P12V             VIA   -     D0100PA00X+030946Y+148010               S3      
317P12V             VIA   -     D0100PA00X+030982Y+147296               S3      
317P12V             VIA   -     D0100PA00X+031246Y+149397               S3      
317P12V             VIA   -     D0100PA00X+031246Y+148702               S3      
317P12V             VIA   -     D0100PA00X+029572Y+148702               S3      
317P12V             VIA   -     D0100PA00X+029572Y+149397               S3      
317P12V             VIA   -     D0100PA00X+030389Y+149397               S3      
317P12V             VIA   -     D0100PA00X+030389Y+148702               S3      
317P12V             VIA   -     D0100PA00X+030089Y+148702               S3      
317P12V             VIA   -     D0100PA00X+030089Y+149397               S3      
317P12V             VIA   -     D0100PA00X+029272Y+149397               S3      
317P12V             VIA   -     D0100PA00X+029272Y+148702               S3      
317P12V             VIA   -     D0100PA00X+030946Y+148702               S3      
317P12V             VIA   -     D0100PA00X+030946Y+149397               S3      
327P12V             R127  -2          A01X+030891Y+152440X0180Y0200R180 S2      
327NNAME10046       R127  -1          A01X+030576Y+152440X0180Y0200R180 S2      
327GND              R128  -2          A01X+030864Y+151388X0180Y0200R180 S2      
327NNAME10038       R128  -1          A01X+030549Y+151388X0180Y0200R180 S2      
317GND              VIA   -     D0100PA00X+031389Y+151388               S3      
317NNAME10046       VIA   -     D0100PA00X+030227Y+152440               S1      
317NNAME10038       VIA   -     D0100PA00X+030173Y+151388               S1      
327GND              C67   -2          A01X+030487Y+154745X0180Y0200R090 S2      
327P12V             C67   -1          A01X+030487Y+155060X0180Y0200R090 S2      
327GND              C69   -2          A01X+029568Y+154745X0180Y0200R090 S2      
327P12V             C69   -1          A01X+029568Y+155060X0180Y0200R090 S2      
327GND              C68   -2          A01X+030039Y+154745X0180Y0200R090 S2      
327P12V             C68   -1          A01X+030039Y+155060X0180Y0200R090 S2      
317GND              VIA   -     D0100PA00X+030487Y+154321               S3      
317GND              VIA   -     D0100PA00X+030039Y+154321               S1      
317GND              VIA   -     D0100PA00X+029568Y+154321               S3      
317T10_BLAD1_EN     VIA   -     D0100PA00X+031208Y+157587               S1      
317P12V             J16   -P20  D0300PA00X+029339Y+159689               S0      
317P12V             J16   -P19  D0300PA00X+030339Y+159689               S0      
317P12V             J16   -P18  D0300PA00X+031339Y+159689               S0      
317P12V             J16   -P13  D0300PA00X+029339Y+160752               S0      
317P12V             J16   -P14  D0300PA00X+030339Y+160752               S0      
317P12V             J16   -P15  D0300PA00X+031339Y+160752               S0      
327P12V             C66   -1          A01X+029409Y+164917X0180Y0200R270 S2      
327GND              C66   -2          A01X+029409Y+165232X0180Y0200R270 S2      
317GND              VIA   -     D0100PA00X+029409Y+165656               S1      
317GND              H3    -6    D0220PA00X+030709Y+167972               S0      
317GND              H3    -5    D0220PA00X+029724Y+168366               S0      
317GND              H3    -4    D0220PA00X+029331Y+169350               S0      
317N/C              H3    -1    D1580UA00X+030709Y+169350               S0      
317GND              H3    -3    D0220PA00X+029724Y+170335               S0      
317GND              H3    -2    D0220PA00X+030709Y+170728               S0      
317P12V             J17   -P20  D0300PA00X+029339Y+177189               S0      
317P12V             J17   -P19  D0300PA00X+030339Y+177189               S0      
317P12V             J17   -P18  D0300PA00X+031339Y+177189               S0      
317P12V             J17   -P13  D0300PA00X+029339Y+178252               S0      
317P12V             J17   -P14  D0300PA00X+030339Y+178252               S0      
317P12V             J17   -P15  D0300PA00X+031339Y+178252               S0      
317P12V             VIA   -     D0100PA00X+029261Y+186457               S3      
317GND              VIA   -     D0100PA00X+029361Y+185867               S3      
317N/C              H13   -1    D2050UA00X+030709Y+188307               S0      
317P12V             VIA   -     D0100PA00X+029575Y+191715               S3      
317P12V             VIA   -     D0100PA00X+030335Y+191715               S3      
317P12V             VIA   -     D0100PA00X+029575Y+191023               S3      
317P12V             VIA   -     D0100PA00X+030335Y+191023               S3      
317P12V             VIA   -     D0100PA00X+031022Y+191041               S3      
317P12V             VIA   -     D0100PA00X+031481Y+191041               S3      
317P12V             VIA   -     D0100PA00X+030722Y+191041               S3      
317P12V             VIA   -     D0100PA00X+030035Y+191023               S3      
317P12V             VIA   -     D0100PA00X+029275Y+191023               S3      
317P12V             VIA   -     D0100PA00X+030035Y+191715               S3      
317P12V             VIA   -     D0100PA00X+029275Y+191715               S3      
317P12V             VIA   -     D0100PA00X+031022Y+191733               S3      
317P12V             VIA   -     D0100PA00X+029575Y+192410               S3      
317P12V             VIA   -     D0100PA00X+030335Y+192410               S3      
317P12V             VIA   -     D0100PA00X+031022Y+192428               S3      
317P12V             VIA   -     D0100PA00X+030722Y+192428               S3      
317P12V             VIA   -     D0100PA00X+031481Y+192428               S3      
317P12V             VIA   -     D0100PA00X+030035Y+192410               S3      
317P12V             VIA   -     D0100PA00X+029275Y+192410               S3      
317P12V             VIA   -     D0100PA00X+030722Y+191733               S3      
317P12V             VIA   -     D0100PA00X+031481Y+191733               S3      
317P12V             J18   -P20  D0300PA00X+029339Y+194689               S0      
317P12V             J18   -P13  D0300PA00X+029339Y+195752               S0      
317P12V             J18   -P19  D0300PA00X+030339Y+194689               S0      
317P12V             J18   -P14  D0300PA00X+030339Y+195752               S0      
317P12V             J18   -P15  D0300PA00X+031339Y+195752               S0      
317P12V             J18   -P18  D0300PA00X+031339Y+194689               S0      
327P12V             C78   -1          A01X+031456Y+199861X0280Y0320     S2      
327GND              C78   -2          A01X+031456Y+200441X0280Y0320     S2      
317GND              VIA   -     D0100PA00X+031456Y+200909               S1      
317GND              H1    -6    D0220PA00X+030709Y+202972               S0      
317GND              H1    -5    D0220PA00X+029724Y+203366               S0      
317N/C              H1    -1    D1580UA00X+030709Y+204350               S0      
317GND              H1    -4    D0220PA00X+029331Y+204350               S0      
317GND              H1    -3    D0220PA00X+029724Y+205335               S0      
317GND              H1    -2    D0220PA00X+030709Y+205728               S0      
317GND              VIA   -     D0100PA00X+030999Y+208361               S3      
317GND              VIA   -     D0100PA00X+032522Y+000300               S3      
317T1_BLAD3_TXD     J7    -S12  D0300PA00X+033717Y+002471               S0      
317P12V             J7    -P16  D0300PA00X+032339Y+003252               S0      
317P12V             J7    -P17  D0300PA00X+032339Y+002189               S0      
317T1_BLAD1_TXD     J7    -S1   D0300PA00X+033717Y+003471               S0      
317T1_BLAD4_RXD     VIA   -     D0100PA00X+033140Y+005141               S1      
317T1_BLAD4_TXD     VIA   -     D0100PA00X+033389Y+005602               S1      
327GND              C6    -2          A01X+031757Y+007539X0180Y0200R270 S2      
327P12V             C6    -1          A01X+031757Y+007224X0180Y0200R270 S2      
327GND              C7    -2          A01X+032201Y+007539X0180Y0200R270 S2      
327P12V             C7    -1          A01X+032201Y+007224X0180Y0200R270 S2      
317T1_BLAD3_RXD     VIA   -     D0100PA00X+033823Y+006156               S1      
317GND              VIA   -     D0100PA00X+032201Y+007878               S1      
317GND              VIA   -     D0100PA00X+031757Y+007878               S3      
317GND              H12   -8    D0220PA00X+032087Y+012717               S0      
317GND              H12   -7    D0220PA00X+031693Y+011732               S0      
317GND              H12   -9    D0220PA00X+031693Y+013701               S0      
317T2_BLAD3_TXD     J8    -S12  D0300PA00X+033717Y+019971               S0      
317P12V             J8    -P17  D0300PA00X+032339Y+019689               S0      
317T2_BLAD1_TXD     J8    -S1   D0300PA00X+033717Y+020971               S0      
317P12V             J8    -P16  D0300PA00X+032339Y+020752               S0      
317T2_BLAD4_TXD     VIA   -     D0100PA00X+032037Y+022598               S1      
317T2_BLAD4_RXD     VIA   -     D0100PA00X+031809Y+023182               S1      
317T2_BLAD2_RXD     VIA   -     D0100PA00X+032190Y+023814               S1      
317T2_BLAD2_TXD     VIA   -     D0100PA00X+033105Y+023202               S1      
317T2_BLAD3_EN      VIA   -     D0100PA00X+032096Y+025011               S1      
317T2_BLAD3_RXD     VIA   -     D0100PA00X+032471Y+023158               S1      
317P12V             VIA   -     D0100PA00X+033278Y+031863               S3      
317P12V             VIA   -     D0100PA00X+033269Y+031198               S3      
317P12V             VIA   -     D0100PA00X+032969Y+031198               S3      
317P12V             VIA   -     D0100PA00X+032978Y+031863               S3      
317P12V             VIA   -     D0100PA00X+033278Y+033527               S3      
317P12V             VIA   -     D0100PA00X+033278Y+034246               S3      
317P12V             VIA   -     D0100PA00X+033278Y+032594               S3      
317P12V             VIA   -     D0100PA00X+032978Y+032594               S3      
317P12V             VIA   -     D0100PA00X+032978Y+034246               S3      
317P12V             VIA   -     D0100PA00X+032978Y+033527               S3      
317P12V             J9    -P17  D0300PA00X+032339Y+037189               S0      
317P12V             VIA   -     D0100PA00X+033269Y+034866               S3      
317P12V             VIA   -     D0100PA00X+032969Y+034866               S3      
317T3_BLAD3_TXD     J9    -S12  D0300PA00X+033717Y+037471               S0      
317T3_BLAD1_TXD     J9    -S1   D0300PA00X+033717Y+038471               S0      
317P12V             J9    -P16  D0300PA00X+032339Y+038252               S0      
317T3_BLAD2_TXD     VIA   -     D0100PA00X+033552Y+040403               S1      
317T3_BLAD4_RXD     VIA   -     D0100PA00X+032331Y+041831               S1      
317T3_BLAD3_TXD     VIA   -     D0100PA00X+032620Y+041398               S1      
317T3_BLAD3_RXD     VIA   -     D0100PA00X+032895Y+040922               S1      
317T3_BLAD4_TXD     VIA   -     D0100PA00X+032098Y+042323               S1      
317GND              H9    -7    D0220PA00X+031693Y+046732               S0      
317GND              H9    -9    D0220PA00X+031693Y+048701               S0      
317GND              H9    -8    D0220PA00X+032087Y+047717               S0      
317P12V             VIA   -     D0100PA00X+032514Y+051663               S3      
317P12V             VIA   -     D0100PA00X+032514Y+052436               S3      
317P12V             VIA   -     D0100PA00X+031679Y+052443               S3      
317P12V             VIA   -     D0100PA00X+031679Y+051670               S3      
317P12V             VIA   -     D0100PA00X+031679Y+053287               S3      
317P12V             VIA   -     D0100PA00X+032514Y+053280               S3      
317P12V             VIA   -     D0100PA00X+032214Y+053280               S3      
317P12V             VIA   -     D0100PA00X+032214Y+052436               S3      
317P12V             VIA   -     D0100PA00X+032214Y+051663               S3      
317T4_BLAD3_TXD     J10   -S12  D0300PA00X+033717Y+054971               S0      
317T4_BLAD1_TXD     J10   -S1   D0300PA00X+033717Y+055971               S0      
317P12V             J10   -P16  D0300PA00X+032339Y+055752               S0      
317P12V             J10   -P17  D0300PA00X+032339Y+054689               S0      
317T4_BLAD3_RXD     VIA   -     D0100PA00X+033662Y+057798               S1      
317T4_BLAD3_EN      VIA   -     D0100PA00X+031931Y+058211               S1      
317T4_BLAD4_TXD     VIA   -     D0100PA00X+032964Y+058472               S1      
317T4_BLAD1_RXD     VIA   -     D0100PA00X+031772Y+058825               S1      
317T4_BLAD2_TXD     VIA   -     D0100PA00X+033739Y+058623               S1      
317T4_BLAD1_TXD     VIA   -     D0100PA00X+032038Y+057649               S1      
317T4_BLAD4_RXD     VIA   -     D0100PA00X+033187Y+058981               S1      
317T4_BLAD3_TXD     VIA   -     D0100PA00X+033375Y+059533               S1      
317T4_BLAD1_EN      VIA   -     D0100PA00X+032174Y+059904               S1      
317P12V             VIA   -     D0100PA00X+031819Y+065246               S3      
317P12V             VIA   -     D0100PA00X+031819Y+067176               S3      
317P12V             VIA   -     D0100PA00X+031819Y+068110               S3      
317P12V             VIA   -     D0100PA00X+031819Y+066126               S3      
317P12V             VIA   -     D0100PA00X+031819Y+069727               S3      
317P12V             VIA   -     D0100PA00X+031819Y+068883               S3      
317T5_BLAD3_TXD     J11   -S12  D0300PA00X+033717Y+072471               S0      
317P12V             J11   -P16  D0300PA00X+032339Y+073252               S0      
317P12V             J11   -P17  D0300PA00X+032339Y+072189               S0      
317T5_BLAD1_TXD     J11   -S1   D0300PA00X+033717Y+073471               S0      
317T5_BLAD3_RXD     VIA   -     D0100PA00X+033157Y+075297               S1      
317T5_BLAD2_TXD     VIA   -     D0100PA00X+033901Y+075286               S1      
317T5_BLAD4_TXD     VIA   -     D0100PA00X+032934Y+076269               S1      
317T5_BLAD3_TXD     VIA   -     D0100PA00X+033401Y+075859               S1      
317T5_BLAD4_RXD     VIA   -     D0100PA00X+032752Y+075802               S1      
317GND              H7    -8    D0220PA00X+032087Y+082717               S0      
317GND              H7    -7    D0220PA00X+031693Y+081732               S0      
317GND              H7    -9    D0220PA00X+031693Y+083701               S0      
317T6_BLAD3_TXD     J12   -S12  D0300PA00X+033717Y+089971               S0      
317P12V             J12   -P17  D0300PA00X+032339Y+089689               S0      
317T6_BLAD1_TXD     J12   -S1   D0300PA00X+033717Y+090971               S0      
317P12V             J12   -P16  D0300PA00X+032339Y+090752               S0      
317T6_BLAD3_TXD     VIA   -     D0100PA00X+032994Y+094876               S1      
317T6_BLAD3_RXD     VIA   -     D0100PA00X+033253Y+094375               S1      
317T6_BLAD1_RXD     VIA   -     D0100PA00X+032410Y+094610               S1      
317T6_BLAD4_TXD     VIA   -     D0100PA00X+031856Y+094118               S1      
317T6_BLAD4_RXD     VIA   -     D0100PA00X+032387Y+092998               S1      
317T6_BLAD3_EN      VIA   -     D0100PA00X+032665Y+093979               S1      
317T6_BLAD2_TXD     VIA   -     D0100PA00X+033616Y+093726               S1      
317T6_BLAD1_EN      VIA   -     D0100PA00X+032858Y+093326               S1      
317T6_BLAD1_TXD     VIA   -     D0100PA00X+032143Y+095158               S1      
317P12V             VIA   -     D0100PA00X+032124Y+102066               S3      
317P12V             VIA   -     D0100PA00X+032132Y+100129               S3      
317P12V             VIA   -     D0100PA00X+032112Y+100730               S3      
317P12V             VIA   -     D0100PA00X+032118Y+101409               S3      
317P12V             VIA   -     D0100PA00X+031818Y+101409               S3      
317P12V             VIA   -     D0100PA00X+031812Y+100730               S3      
317P12V             VIA   -     D0100PA00X+031832Y+100129               S3      
317P12V             VIA   -     D0100PA00X+031824Y+102066               S3      
317P12V             VIA   -     D0100PA00X+032117Y+102708               S3      
317P12V             VIA   -     D0100PA00X+032104Y+103372               S3      
317P12V             VIA   -     D0100PA00X+031804Y+103372               S3      
317P12V             VIA   -     D0100PA00X+031817Y+102708               S3      
317P12V             J13   -P17  D0300PA00X+032339Y+107189               S0      
317T7_BLAD3_RXD     VIA   -     D0100PA00X+032425Y+105179               S1      
317T7_BLAD4_RXD     VIA   -     D0100PA00X+033568Y+104890               S1      
317T7_BLAD3_TXD     VIA   -     D0100PA00X+031759Y+105305               S1      
317T7_BLAD3_TXD     J13   -S12  D0300PA00X+033717Y+107471               S0      
317T7_BLAD1_TXD     J13   -S1   D0300PA00X+033717Y+108471               S0      
317P12V             J13   -P16  D0300PA00X+032339Y+108252               S0      
317T7_BLAD1_EN      VIA   -     D0100PA00X+033751Y+110960               S1      
317T7_BLAD1_RXD     VIA   -     D0100PA00X+032899Y+112109               S1      
317T7_BLAD1_TXD     VIA   -     D0100PA00X+032656Y+112637               S1      
327GND              R124  -2          A01X+032021Y+116227X0180Y0200R180 S2      
327NNAME10036       R124  -1          A01X+031706Y+116227X0180Y0200R180 S2      
317GND              VIA   -     D0100PA00X+032580Y+116227               S3      
327P12V             R123  -2          A01X+032026Y+117280X0180Y0200R180 S2      
327NNAME10045       R123  -1          A01X+031711Y+117280X0180Y0200R180 S2      
317P12V             VIA   -     D0100PA00X+031794Y+119225               S3      
317P12V             VIA   -     D0100PA00X+031794Y+118453               S3      
317P12V             VIA   -     D0100PA00X+032094Y+118453               S3      
317P12V             VIA   -     D0100PA00X+032094Y+119225               S3      
317P12V             VIA   -     D0100PA00X+032340Y+117280               S3      
317P12V             VIA   -     D0100PA00X+031794Y+120069               S3      
317P12V             VIA   -     D0100PA00X+032094Y+120069               S3      
317T8_BLAD3_TXD     J14   -S12  D0300PA00X+033717Y+124971               S0      
317T8_BLAD1_TXD     J14   -S1   D0300PA00X+033717Y+125971               S0      
317P12V             J14   -P16  D0300PA00X+032339Y+125752               S0      
317P12V             J14   -P17  D0300PA00X+032339Y+124689               S0      
317T8_BLAD1_RXD     VIA   -     D0100PA00X+032745Y+127945               S1      
317T8_BLAD1_TXD     VIA   -     D0100PA00X+032198Y+128209               S1      
317T8_BLAD1_EN      VIA   -     D0100PA00X+032962Y+128402               S1      
317T8_BLAD3_EN      VIA   -     D0100PA00X+032793Y+128922               S1      
317GND              H5    -7    D0220PA00X+031693Y+133366               S0      
317GND              H5    -9    D0220PA00X+031693Y+135335               S0      
317GND              H5    -8    D0220PA00X+032087Y+134350               S0      
317T9_BLAD1_RXD     VIA   -     D0100PA00X+032564Y+139911               S1      
317T9_BLAD4_TXD     VIA   -     D0100PA00X+033465Y+140080               S1      
317T9_BLAD3_TXD     J15   -S12  D0300PA00X+033717Y+142471               S0      
317T9_BLAD1_TXD     J15   -S1   D0300PA00X+033717Y+143471               S0      
317P12V             J15   -P16  D0300PA00X+032339Y+143252               S0      
317P12V             J15   -P17  D0300PA00X+032339Y+142189               S0      
317T10_BLAD3_EN     VIA   -     D0100PA00X+032372Y+157092               S1      
317T10_BLAD1_TXD    VIA   -     D0100PA00X+033347Y+156669               S1      
317T10_BLAD1_RXD    VIA   -     D0100PA00X+033596Y+157380               S1      
317T10_BLAD3_TXD    J16   -S12  D0300PA00X+033717Y+159971               S0      
317P12V             J16   -P17  D0300PA00X+032339Y+159689               S0      
317T10_BLAD1_TXD    J16   -S1   D0300PA00X+033717Y+160971               S0      
317P12V             J16   -P16  D0300PA00X+032339Y+160752               S0      
317GND              H3    -8    D0220PA00X+032087Y+169350               S0      
317GND              H3    -7    D0220PA00X+031693Y+168366               S0      
317GND              H3    -9    D0220PA00X+031693Y+170335               S0      
317P12V             J17   -P17  D0300PA00X+032339Y+177189               S0      
317T11_BLAD1_EN     VIA   -     D0100PA00X+032381Y+175323               S1      
317T11_BLAD3_EN     VIA   -     D0100PA00X+032989Y+175208               S1      
317T11_BLAD3_TXD    J17   -S12  D0300PA00X+033717Y+177471               S0      
317T11_BLAD1_TXD    J17   -S1   D0300PA00X+033717Y+178471               S0      
317P12V             J17   -P16  D0300PA00X+032339Y+178252               S0      
317P12V             VIA   -     D0100PA00X+031781Y+191041               S3      
317T12_BLAD1_EN     VIA   -     D0100PA00X+033240Y+192679               S1      
317P12V             VIA   -     D0100PA00X+031781Y+191733               S3      
317P12V             VIA   -     D0100PA00X+031781Y+192428               S3      
317T12_BLAD3_TXD    J18   -S12  D0300PA00X+033717Y+194971               S0      
317T12_BLAD1_TXD    J18   -S1   D0300PA00X+033717Y+195971               S0      
317P12V             J18   -P16  D0300PA00X+032339Y+195752               S0      
317P12V             J18   -P17  D0300PA00X+032339Y+194689               S0      
327GND              C79   -2          A01X+032005Y+200203X0180Y0200R270 S2      
327P12V             C79   -1          A01X+032005Y+199888X0180Y0200R270 S2      
327GND              C80   -2          A01X+032480Y+200203X0180Y0200R270 S2      
327P12V             C80   -1          A01X+032480Y+199888X0180Y0200R270 S2      
317GND              VIA   -     D0100PA00X+032480Y+200527               S1      
317GND              VIA   -     D0100PA00X+032005Y+200522               S3      
317GND              H1    -7    D0220PA00X+031693Y+203366               S0      
317GND              H1    -9    D0220PA00X+031693Y+205335               S0      
317GND              H1    -8    D0220PA00X+032087Y+204350               S0      
317T1_BLAD3_RXD     J7    -S11  D0300PA00X+034217Y+001971               S0      
317T1_BLAD1_RXD     J7    -S2   D0300PA00X+034217Y+002971               S0      
317T1_BLAD3_EN      J7    -S10  D0300PA00X+034717Y+002471               S0      
317B2_PSU_ALERT_N   J7    -S9   D0300PA00X+035217Y+001971               S0      
317B1_PSU_ALERT_N   J7    -S4   D0300PA00X+035217Y+002971               S0      
317T1_BLAD4_TXD     J7    -S8   D0300PA00X+035717Y+002471               S0      
317T1_BLAD4_RXD     J7    -S7   D0300PA00X+036217Y+001971               S0      
317T1_BLAD2_RXD     J7    -S6   D0300PA00X+036217Y+002971               S0      
317T1_BLAD1_EN      J7    -S3   D0300PA00X+034717Y+003471               S0      
317T1_BLAD2_TXD     J7    -S5   D0300PA00X+035717Y+003471               S0      
317T1_BLAD1_TXD     VIA   -     D0100PA00X+035993Y+005219               S1      
317T1_BLAD2_TXD     VIA   -     D0100PA00X+034829Y+005086               S1      
317T1_BLAD2_RXD     VIA   -     D0100PA00X+034509Y+005619               S1      
317T1_BLAD3_TXD     VIA   -     D0100PA00X+034037Y+005158               S1      
317N/C              H25   -1    D3150UA00X+035984Y+007878               S0      
317T2_BLAD3_RXD     J8    -S11  D0300PA00X+034217Y+019471               S0      
317T2_BLAD3_EN      J8    -S10  D0300PA00X+034717Y+019971               S0      
317B4_PSU_ALERT_N   J8    -S9   D0300PA00X+035217Y+019471               S0      
317T2_BLAD4_TXD     J8    -S8   D0300PA00X+035717Y+019971               S0      
317T2_BLAD4_RXD     J8    -S7   D0300PA00X+036217Y+019471               S0      
317T2_BLAD1_RXD     J8    -S2   D0300PA00X+034217Y+020471               S0      
317T2_BLAD1_EN      J8    -S3   D0300PA00X+034717Y+020971               S0      
317B3_PSU_ALERT_N   J8    -S4   D0300PA00X+035217Y+020471               S0      
317T2_BLAD2_TXD     J8    -S5   D0300PA00X+035717Y+020971               S0      
317T2_BLAD2_RXD     J8    -S6   D0300PA00X+036217Y+020471               S0      
317N/C              H16   -1    D3150UA00X+035984Y+025378               S0      
327GND              U4    -7          A08X+035968Y+030689X0140Y0590     S1      
327B3_PSU_ALERT_N   U4    -6          A08X+036224Y+030689X0140Y0590     S1      
317P12V             VIA   -     D0100PA00X+034382Y+031863               S3      
317P12V             VIA   -     D0100PA00X+034373Y+031198               S3      
317P12V             VIA   -     D0100PA00X+034073Y+031198               S3      
317P12V             VIA   -     D0100PA00X+034082Y+031863               S3      
317GND              VIA   -     D0100PA00X+036180Y+031194               S3      
327B3_PSU_ALERT_N   VIA   -           A08X+036223Y+029938X0260Y0260     S1      
327B4_PSU_ALERT_N   VIA   -           A08X+035683Y+029996X0260Y0260     S1      
327PSU_ALERT_N      U4    -9          A08X+036224Y+032989X0140Y0590     S1      
327B4_PSU_ALERT_N   U4    -8          A08X+035968Y+032989X0140Y0590     S1      
317P12V             VIA   -     D0100PA00X+034382Y+033527               S3      
317P12V             VIA   -     D0100PA00X+034382Y+034246               S3      
317P12V             VIA   -     D0100PA00X+034382Y+032594               S3      
317P12V             VIA   -     D0100PA00X+034082Y+032594               S3      
317P12V             VIA   -     D0100PA00X+034082Y+034246               S3      
317P12V             VIA   -     D0100PA00X+034082Y+033527               S3      
317PSU_ALERT_N      VIA   -     D0100PA00X+036224Y+032498               S3      
327B5_PSU_ALERT_N   VIA   -           A08X+036053Y+033910X0260Y0260     S1      
317T3_BLAD3_RXD     J9    -S11  D0300PA00X+034217Y+036971               S0      
317B6_PSU_ALERT_N   J9    -S9   D0300PA00X+035217Y+036971               S0      
317T3_BLAD4_RXD     J9    -S7   D0300PA00X+036217Y+036971               S0      
317P12V             VIA   -     D0100PA00X+034373Y+034866               S3      
317P12V             VIA   -     D0100PA00X+034073Y+034866               S3      
317T3_BLAD1_RXD     J9    -S2   D0300PA00X+034217Y+037971               S0      
317T3_BLAD3_EN      J9    -S10  D0300PA00X+034717Y+037471               S0      
317T3_BLAD1_EN      J9    -S3   D0300PA00X+034717Y+038471               S0      
317B5_PSU_ALERT_N   J9    -S4   D0300PA00X+035217Y+037971               S0      
317T3_BLAD4_TXD     J9    -S8   D0300PA00X+035717Y+037471               S0      
317T3_BLAD2_TXD     J9    -S5   D0300PA00X+035717Y+038471               S0      
317T3_BLAD2_RXD     J9    -S6   D0300PA00X+036217Y+037971               S0      
317N/C              H17   -1    D3150UA00X+035984Y+042878               S0      
317T3_BLAD2_RXD     VIA   -     D0100PA00X+034210Y+040168               S1      
317T3_BLAD1_TXD     VIA   -     D0100PA00X+036383Y+040177               S1      
317T4_BLAD3_RXD     J10   -S11  D0300PA00X+034217Y+054471               S0      
317T4_BLAD1_RXD     J10   -S2   D0300PA00X+034217Y+055471               S0      
317T4_BLAD3_EN      J10   -S10  D0300PA00X+034717Y+054971               S0      
317T4_BLAD1_EN      J10   -S3   D0300PA00X+034717Y+055971               S0      
317B8_PSU_ALERT_N   J10   -S9   D0300PA00X+035217Y+054471               S0      
317B7_PSU_ALERT_N   J10   -S4   D0300PA00X+035217Y+055471               S0      
317T4_BLAD4_TXD     J10   -S8   D0300PA00X+035717Y+054971               S0      
317T4_BLAD2_TXD     J10   -S5   D0300PA00X+035717Y+055971               S0      
317T4_BLAD4_RXD     J10   -S7   D0300PA00X+036217Y+054471               S0      
317T4_BLAD2_RXD     J10   -S6   D0300PA00X+036217Y+055471               S0      
317N/C              H22   -1    D3150UA00X+035984Y+060378               S0      
317T4_BLAD2_RXD     VIA   -     D0100PA00X+034290Y+058013               S1      
327GND              U5    -7          A08X+035400Y+065699X0140Y0590     S1      
327B9_PSU_ALERT_N   U5    -6          A08X+035656Y+065699X0140Y0590     S1      
327PSU_ALERT_N      U5    -5          A08X+035912Y+065699X0140Y0590     S1      
327B8_PSU_ALERT_N   U5    -4          A08X+036168Y+065699X0140Y0590     S1      
317GND              VIA   -     D0100PA00X+035400Y+065217               S3      
327B7_PSU_ALERT_N   VIA   -           A08X+036435Y+065051X0260Y0260     S1      
327B8_PSU_ALERT_N   VIA   -           A08X+035891Y+065053X0260Y0260     S1      
327PSU_ALERT_N      U5    -11         A08X+036168Y+067999X0140Y0590     S1      
327NNAME10049       U5    -10         A08X+035912Y+067999X0140Y0590     S1      
327PSU_ALERT_N      U5    -9          A08X+035656Y+067999X0140Y0590     S1      
327NNAME10050       U5    -8          A08X+035400Y+067999X0140Y0590     S1      
317PSU_ALERT_N      VIA   -     D0100PA00X+035656Y+067517               S3      
327B9_PSU_ALERT_N   VIA   -           A08X+034723Y+069408X0260Y0260     S1      
327NNAME10050       VIA   -           A08X+035236Y+069836X0260Y0260     S1      
327NNAME10049       VIA   -           A08X+036253Y+069442X0260Y0260     S1      
317T5_BLAD3_RXD     J11   -S11  D0300PA00X+034217Y+071971               S0      
317T5_BLAD1_RXD     J11   -S2   D0300PA00X+034217Y+072971               S0      
317T5_BLAD3_EN      J11   -S10  D0300PA00X+034717Y+072471               S0      
317NNAME10050       J11   -S9   D0300PA00X+035217Y+071971               S0      
317B9_PSU_ALERT_N   J11   -S4   D0300PA00X+035217Y+072971               S0      
317T5_BLAD4_TXD     J11   -S8   D0300PA00X+035717Y+072471               S0      
317T5_BLAD4_RXD     J11   -S7   D0300PA00X+036217Y+071971               S0      
317T5_BLAD2_RXD     J11   -S6   D0300PA00X+036217Y+072971               S0      
317T5_BLAD1_EN      J11   -S3   D0300PA00X+034717Y+073471               S0      
317T5_BLAD2_TXD     J11   -S5   D0300PA00X+035717Y+073471               S0      
317T5_BLAD1_TXD     VIA   -     D0100PA00X+036258Y+075278               S1      
317T5_BLAD2_RXD     VIA   -     D0100PA00X+034411Y+075181               S1      
317N/C              H20   -1    D3150UA00X+035984Y+077878               S0      
317T6_BLAD3_RXD     J12   -S11  D0300PA00X+034217Y+089471               S0      
317T6_BLAD3_EN      J12   -S10  D0300PA00X+034717Y+089971               S0      
317NNAME10051       J12   -S9   D0300PA00X+035217Y+089471               S0      
317T6_BLAD4_TXD     J12   -S8   D0300PA00X+035717Y+089971               S0      
317T6_BLAD4_RXD     J12   -S7   D0300PA00X+036217Y+089471               S0      
317T6_BLAD1_RXD     J12   -S2   D0300PA00X+034217Y+090471               S0      
317T6_BLAD1_EN      J12   -S3   D0300PA00X+034717Y+090971               S0      
317NNAME10049       J12   -S4   D0300PA00X+035217Y+090471               S0      
317T6_BLAD2_TXD     J12   -S5   D0300PA00X+035717Y+090971               S0      
317T6_BLAD2_RXD     J12   -S6   D0300PA00X+036217Y+090471               S0      
317N/C              H18   -1    D3150UA00X+035984Y+095378               S0      
317T6_BLAD2_RXD     VIA   -     D0100PA00X+034366Y+093373               S1      
317T7_BLAD3_RXD     J13   -S11  D0300PA00X+034217Y+106971               S0      
317NNAME10052       J13   -S9   D0300PA00X+035217Y+106971               S0      
317T7_BLAD4_RXD     J13   -S7   D0300PA00X+036217Y+106971               S0      
317T7_BLAD4_TXD     VIA   -     D0100PA00X+034558Y+104784               S1      
317T7_BLAD1_RXD     J13   -S2   D0300PA00X+034217Y+107971               S0      
317T7_BLAD3_EN      J13   -S10  D0300PA00X+034717Y+107471               S0      
317T7_BLAD1_EN      J13   -S3   D0300PA00X+034717Y+108471               S0      
317NNAME10053       J13   -S4   D0300PA00X+035217Y+107971               S0      
317T7_BLAD4_TXD     J13   -S8   D0300PA00X+035717Y+107471               S0      
317T7_BLAD2_TXD     J13   -S5   D0300PA00X+035717Y+108471               S0      
317T7_BLAD2_RXD     J13   -S6   D0300PA00X+036217Y+107971               S0      
317N/C              H21   -1    D3150UA00X+035984Y+112878               S0      
317T7_BLAD3_EN      VIA   -     D0100PA00X+034410Y+110680               S1      
317T8_BLAD3_RXD     J14   -S11  D0300PA00X+034217Y+124471               S0      
317T8_BLAD1_RXD     J14   -S2   D0300PA00X+034217Y+125471               S0      
317T8_BLAD3_EN      J14   -S10  D0300PA00X+034717Y+124971               S0      
317T8_BLAD1_EN      J14   -S3   D0300PA00X+034717Y+125971               S0      
317NNAME10054       J14   -S9   D0300PA00X+035217Y+124471               S0      
317NNAME10055       J14   -S4   D0300PA00X+035217Y+125471               S0      
317T8_BLAD4_TXD     J14   -S8   D0300PA00X+035717Y+124971               S0      
317T8_BLAD2_TXD     J14   -S5   D0300PA00X+035717Y+125971               S0      
317T8_BLAD4_RXD     J14   -S7   D0300PA00X+036217Y+124471               S0      
317T8_BLAD2_RXD     J14   -S6   D0300PA00X+036217Y+125471               S0      
317N/C              H26   -1    D3150UA00X+035984Y+130378               S0      
317GND              VIA   -     D0100PA00X+036317Y+132969               S3      
317GND              VIA   -     D0100PA00X+035139Y+132969               S3      
317GND              VIA   -     D0100PA00X+035439Y+132969               S3      
317GND              VIA   -     D0100PA00X+036317Y+135071               S3      
317GND              VIA   -     D0100PA00X+036317Y+136004               S3      
317GND              VIA   -     D0100PA00X+036317Y+134020               S3      
317GND              VIA   -     D0100PA00X+035139Y+135071               S3      
317GND              VIA   -     D0100PA00X+035139Y+136004               S3      
317GND              VIA   -     D0100PA00X+035139Y+134020               S3      
317GND              VIA   -     D0100PA00X+035439Y+134020               S3      
317GND              VIA   -     D0100PA00X+035439Y+136004               S3      
317GND              VIA   -     D0100PA00X+035439Y+135071               S3      
317GND              VIA   -     D0100PA00X+036317Y+137621               S3      
317GND              VIA   -     D0100PA00X+036317Y+136777               S3      
317GND              VIA   -     D0100PA00X+035139Y+137621               S3      
317GND              VIA   -     D0100PA00X+035139Y+136777               S3      
317GND              VIA   -     D0100PA00X+035439Y+136777               S3      
317GND              VIA   -     D0100PA00X+035439Y+137621               S3      
317T9_BLAD4_RXD     VIA   -     D0100PA00X+034413Y+140167               S1      
317T9_BLAD1_TXD     VIA   -     D0100PA00X+035069Y+140324               S1      
317T9_BLAD3_RXD     J15   -S11  D0300PA00X+034217Y+141971               S0      
317T9_BLAD1_RXD     J15   -S2   D0300PA00X+034217Y+142971               S0      
317T9_BLAD3_EN      J15   -S10  D0300PA00X+034717Y+142471               S0      
317T9_BLAD1_EN      J15   -S3   D0300PA00X+034717Y+143471               S0      
317NNAME10056       J15   -S9   D0300PA00X+035217Y+141971               S0      
317NNAME10057       J15   -S4   D0300PA00X+035217Y+142971               S0      
317T9_BLAD4_TXD     J15   -S8   D0300PA00X+035717Y+142471               S0      
317T9_BLAD2_TXD     J15   -S5   D0300PA00X+035717Y+143471               S0      
317T9_BLAD4_RXD     J15   -S7   D0300PA00X+036217Y+141971               S0      
317T9_BLAD2_RXD     J15   -S6   D0300PA00X+036217Y+142971               S0      
317N/C              H23   -1    D3150UA00X+035984Y+147878               S0      
317T10_BLAD2_TXD    VIA   -     D0100PA00X+034871Y+157019               S1      
317T10_BLAD4_TXD    VIA   -     D0100PA00X+036101Y+156889               S1      
317T10_BLAD2_RXD    VIA   -     D0100PA00X+034340Y+157208               S1      
317T10_BLAD3_TXD    VIA   -     D0100PA00X+034825Y+157524               S1      
317T10_BLAD3_RXD    VIA   -     D0100PA00X+035536Y+157099               S1      
317T10_BLAD3_RXD    J16   -S11  D0300PA00X+034217Y+159471               S0      
317T10_BLAD3_EN     J16   -S10  D0300PA00X+034717Y+159971               S0      
317NNAME10058       J16   -S9   D0300PA00X+035217Y+159471               S0      
317T10_BLAD4_TXD    J16   -S8   D0300PA00X+035717Y+159971               S0      
317T10_BLAD4_RXD    J16   -S7   D0300PA00X+036217Y+159471               S0      
317T10_BLAD1_RXD    J16   -S2   D0300PA00X+034217Y+160471               S0      
317T10_BLAD1_EN     J16   -S3   D0300PA00X+034717Y+160971               S0      
317NNAME10059       J16   -S4   D0300PA00X+035217Y+160471               S0      
317T10_BLAD2_TXD    J16   -S5   D0300PA00X+035717Y+160971               S0      
317T10_BLAD2_RXD    J16   -S6   D0300PA00X+036217Y+160471               S0      
317N/C              H15   -1    D3150UA00X+035984Y+165378               S0      
317T11_BLAD3_RXD    J17   -S11  D0300PA00X+034217Y+176971               S0      
317NNAME10060       J17   -S9   D0300PA00X+035217Y+176971               S0      
317T11_BLAD4_RXD    J17   -S7   D0300PA00X+036217Y+176971               S0      
317T11_BLAD1_RXD    J17   -S2   D0300PA00X+034217Y+177971               S0      
317T11_BLAD3_EN     J17   -S10  D0300PA00X+034717Y+177471               S0      
317T11_BLAD1_EN     J17   -S3   D0300PA00X+034717Y+178471               S0      
317NNAME10061       J17   -S4   D0300PA00X+035217Y+177971               S0      
317T11_BLAD4_TXD    J17   -S8   D0300PA00X+035717Y+177471               S0      
317T11_BLAD2_TXD    J17   -S5   D0300PA00X+035717Y+178471               S0      
317T11_BLAD2_RXD    J17   -S6   D0300PA00X+036217Y+177971               S0      
317N/C              H19   -1    D3150UA00X+035984Y+182878               S0      
327GND              U7    -7          A08X+035198Y+188201X0140Y0590     S1      
327NNAME10061       U7    -6          A08X+035454Y+188201X0140Y0590     S1      
327PSU_ALERT_N      U7    -5          A08X+035710Y+188201X0140Y0590     S1      
327NNAME10058       U7    -4          A08X+035966Y+188201X0140Y0590     S1      
327PSU_ALERT_N      U7    -3          A08X+036222Y+188201X0140Y0590     S1      
317GND              VIA   -     D0100PA00X+035234Y+188729               S3      
327NNAME10058       VIA   -           A08X+036104Y+187568X0260Y0260     S1      
327NNAME10061       VIA   -           A08X+035325Y+187431X0260Y0260     S1      
327NNAME10060       VIA   -           A08X+034711Y+187519X0260Y0260     S1      
327NNAME10062       U7    -12         A08X+036222Y+190501X0140Y0590     S1      
327PSU_ALERT_N      U7    -11         A08X+035966Y+190501X0140Y0590     S1      
327NNAME10063       U7    -10         A08X+035710Y+190501X0140Y0590     S1      
327PSU_ALERT_N      U7    -9          A08X+035454Y+190501X0140Y0590     S1      
327NNAME10060       U7    -8          A08X+035198Y+190501X0140Y0590     S1      
317T12_BLAD1_RXD    VIA   -     D0100PA00X+034554Y+191656               S1      
317T12_BLAD1_TXD    VIA   -     D0100PA00X+034440Y+191112               S1      
327NNAME10063       VIA   -           A08X+035373Y+191421X0260Y0260     S1      
327NNAME10062       VIA   -           A08X+036012Y+191241X0260Y0260     S1      
317T12_BLAD2_TXD    VIA   -     D0100PA00X+036336Y+191831               S1      
317T12_BLAD2_RXD    VIA   -     D0100PA00X+035832Y+192068               S1      
317T12_BLAD3_RXD    VIA   -     D0100PA00X+036341Y+192346               S1      
317T12_BLAD3_EN     VIA   -     D0100PA00X+034034Y+192241               S1      
317T12_BLAD3_RXD    J18   -S11  D0300PA00X+034217Y+194471               S0      
317T12_BLAD1_RXD    J18   -S2   D0300PA00X+034217Y+195471               S0      
317T12_BLAD3_EN     J18   -S10  D0300PA00X+034717Y+194971               S0      
317T12_BLAD1_EN     J18   -S3   D0300PA00X+034717Y+195971               S0      
317NNAME10062       J18   -S9   D0300PA00X+035217Y+194471               S0      
317NNAME10063       J18   -S4   D0300PA00X+035217Y+195471               S0      
317T12_BLAD4_TXD    J18   -S8   D0300PA00X+035717Y+194971               S0      
317T12_BLAD2_TXD    J18   -S5   D0300PA00X+035717Y+195971               S0      
317T12_BLAD4_RXD    J18   -S7   D0300PA00X+036217Y+194471               S0      
317T12_BLAD2_RXD    J18   -S6   D0300PA00X+036217Y+195471               S0      
317N/C              H24   -1    D3150UA00X+035984Y+200378               S0      
327N/C                    -1          A08X+034483Y+203527X0390Y0390     S1      
317GND              VIA   -     D0100PA00X+035999Y+208361               S3      
317GND              VIA   -     D0100PA00X+037522Y+000300               S3      
317N/C              J7    -H1   D0990UA00X+037339Y+003252               S0      
317T1_BLAD1_EN      VIA   -     D0100PA00X+037220Y+005613               S1      
317T1_BLAD3_EN      VIA   -     D0100PA00X+037926Y+005216               S1      
327N/C                    -1          A01X+038859Y+006211X0390Y0390     S2      
327N/C                    -1          A08X+038957Y+006618X0390Y0390     S1      
317T1_BLAD1_RXD     VIA   -     D0100PA00X+038752Y+007685               S1      
317N/C              J8    -H1   D0990UA00X+037339Y+020752               S0      
327PSU_ALERT_N      U4    -5          A08X+036480Y+030689X0140Y0590     S1      
327B2_PSU_ALERT_N   U4    -4          A08X+036735Y+030689X0140Y0590     S1      
327PSU_ALERT_N      U4    -3          A08X+036991Y+030689X0140Y0590     S1      
327B1_PSU_ALERT_N   U4    -2          A08X+037247Y+030689X0140Y0590     S1      
327PSU_ALERT_N      U4    -1          A08X+037503Y+030689X0140Y0590     S1      
327B1_PSU_ALERT_N   VIA   -           A08X+037394Y+030052X0260Y0260     S1      
327B2_PSU_ALERT_N   VIA   -           A08X+036854Y+030047X0260Y0260     S1      
327GND              C93   -2          A08X+038515Y+033369X0180Y0200R090 S1      
327P3V3_BUF         C93   -1          A08X+038515Y+033054X0180Y0200R090 S1      
327PSU_ALERT_N      R162  -2          A08X+038092Y+033367X0180Y0200R090 S1      
327P3V3_BUF         R162  -1          A08X+038092Y+033052X0180Y0200R090 S1      
327P3V3_BUF         U4    -14         A08X+037503Y+032989X0140Y0590     S1      
327PSU_ALERT_N      U4    -13         A08X+037247Y+032989X0140Y0590     S1      
327B6_PSU_ALERT_N   U4    -12         A08X+036991Y+032989X0140Y0590     S1      
327PSU_ALERT_N      U4    -11         A08X+036735Y+032989X0140Y0590     S1      
327B5_PSU_ALERT_N   U4    -10         A08X+036480Y+032989X0140Y0590     S1      
327B6_PSU_ALERT_N   VIA   -           A08X+036708Y+034010X0260Y0260     S1      
317N/C              J9    -H1   D0990UA00X+037339Y+038252               S0      
317T3_BLAD1_RXD     VIA   -     D0100PA00X+037444Y+040686               S1      
317T3_BLAD1_EN      VIA   -     D0100PA00X+037454Y+040128               S1      
317T3_BLAD3_EN      VIA   -     D0100PA00X+036891Y+040431               S1      
317N/C              J10   -H1   D0990UA00X+037339Y+055752               S0      
327PSU_ALERT_N      U5    -3          A08X+036424Y+065699X0140Y0590     S1      
327B7_PSU_ALERT_N   U5    -2          A08X+036680Y+065699X0140Y0590     S1      
327PSU_ALERT_N      U5    -1          A08X+036935Y+065699X0140Y0590     S1      
327GND              C94   -2          A08X+037900Y+067291X0180Y0200     S1      
327P3V3_BUF         C94   -1          A08X+037585Y+067291X0180Y0200     S1      
327P3V3_BUF         U5    -14         A08X+036935Y+067999X0140Y0590     S1      
327PSU_ALERT_N      U5    -13         A08X+036680Y+067999X0140Y0590     S1      
327NNAME10051       U5    -12         A08X+036424Y+067999X0140Y0590     S1      
327NNAME10051       VIA   -           A08X+036868Y+069467X0260Y0260     S1      
317N/C              J11   -H1   D0990UA00X+037339Y+073252               S0      
317T5_BLAD1_EN      VIA   -     D0100PA00X+037665Y+075475               S1      
317T5_BLAD1_RXD     VIA   -     D0100PA00X+038289Y+076771               S1      
317T5_BLAD3_EN      VIA   -     D0100PA00X+038679Y+077434               S1      
317N/C              J12   -H1   D0990UA00X+037339Y+090752               S0      
317N/C              J13   -H1   D0990UA00X+037339Y+108252               S0      
317T8_BLAD3_TXD     VIA   -     D0100PA00X+037934Y+118978               S1      
317T8_BLAD4_RXD     VIA   -     D0100PA00X+038328Y+118414               S1      
317T8_BLAD4_TXD     VIA   -     D0100PA00X+038682Y+117984               S1      
317T8_BLAD3_RXD     VIA   -     D0100PA00X+037647Y+119500               S1      
317T8_BLAD2_RXD     VIA   -     D0100PA00X+037367Y+119997               S1      
317T8_BLAD2_TXD     VIA   -     D0100PA00X+037152Y+120473               S1      
317N/C              J14   -H1   D0990UA00X+037339Y+125752               S0      
317GND              VIA   -     D0100PA00X+036617Y+132969               S3      
327NNAME10053       VIA   -           A08X+038526Y+133469X0260Y0260     S1      
327NNAME10055       VIA   -           A08X+037890Y+133384X0260Y0260     S1      
327GND              U6    -7          A08X+037212Y+134726X0140Y0590     S1      
327NNAME10055       U6    -6          A08X+037468Y+134726X0140Y0590     S1      
327PSU_ALERT_N      U6    -5          A08X+037724Y+134726X0140Y0590     S1      
327NNAME10052       U6    -4          A08X+037980Y+134726X0140Y0590     S1      
327PSU_ALERT_N      U6    -3          A08X+038236Y+134726X0140Y0590     S1      
327NNAME10053       U6    -2          A08X+038492Y+134726X0140Y0590     S1      
327PSU_ALERT_N      U6    -1          A08X+038748Y+134726X0140Y0590     S1      
317GND              VIA   -     D0100PA00X+036617Y+134020               S3      
317GND              VIA   -     D0100PA00X+036617Y+136004               S3      
317GND              VIA   -     D0100PA00X+036617Y+135071               S3      
317GND              VIA   -     D0100PA00X+037356Y+135255               S3      
327NNAME10052       VIA   -           A08X+038173Y+134079X0260Y0260     S1      
327NNAME10054       VIA   -           A08X+037350Y+134073X0260Y0260     S1      
327GND              C95   -2          A08X+038487Y+137777X0180Y0200R180 S1      
327P3V3_BUF         C95   -1          A08X+038802Y+137777X0180Y0200R180 S1      
327P3V3_BUF         U6    -14         A08X+038748Y+137026X0140Y0590     S1      
327PSU_ALERT_N      U6    -13         A08X+038492Y+137026X0140Y0590     S1      
327NNAME10056       U6    -12         A08X+038236Y+137026X0140Y0590     S1      
327PSU_ALERT_N      U6    -11         A08X+037980Y+137026X0140Y0590     S1      
327NNAME10057       U6    -10         A08X+037724Y+137026X0140Y0590     S1      
327PSU_ALERT_N      U6    -9          A08X+037468Y+137026X0140Y0590     S1      
327NNAME10054       U6    -8          A08X+037212Y+137026X0140Y0590     S1      
317GND              VIA   -     D0100PA00X+036617Y+136777               S3      
317GND              VIA   -     D0100PA00X+036617Y+137621               S3      
317PSU_ALERT_N      VIA   -     D0100PA00X+037468Y+136562               S3      
327NNAME10057       VIA   -           A08X+037798Y+138314X0260Y0260     S1      
327NNAME10056       VIA   -           A08X+038038Y+137723X0260Y0260     S1      
317N/C              J15   -H1   D0990UA00X+037339Y+143252               S0      
317T10_BLAD4_RXD    VIA   -     D0100PA00X+036783Y+156611               S1      
317N/C              J16   -H1   D0990UA00X+037339Y+160752               S0      
317N/C              J17   -H1   D0990UA00X+037339Y+178252               S0      
327NNAME10059       U7    -2          A08X+036478Y+188201X0140Y0590     S1      
327PSU_ALERT_N      U7    -1          A08X+036734Y+188201X0140Y0590     S1      
327NNAME10059       VIA   -           A08X+036592Y+187048X0260Y0260     S1      
327GND              C96   -2          A08X+038193Y+190175X0180Y0200     S1      
327P3V3_BUF         C96   -1          A08X+037878Y+190175X0180Y0200     S1      
327P3V3_BUF         U7    -14         A08X+036734Y+190501X0140Y0590     S1      
327PSU_ALERT_N      U7    -13         A08X+036478Y+190501X0140Y0590     S1      
317PSU_ALERT_N      VIA   -     D0100PA00X+036631Y+189986               S3      
317P3V3_BUF         VIA   -     D0100PA00X+037443Y+190140               S1      
317T12_BLAD4_TXD    VIA   -     D0100PA00X+037478Y+191924               S1      
317T12_BLAD4_RXD    VIA   -     D0100PA00X+037940Y+191726               S1      
317T12_BLAD3_TXD    VIA   -     D0100PA00X+036975Y+192180               S1      
317N/C              J18   -H1   D0990UA00X+037339Y+195752               S0      
327N/C                    -1          A01X+038562Y+199157X0390Y0390     S2      
317GND              VIA   -     D0100PA00X+040251Y+001711               S3      
317GND              VIA   -     D0100PA00X+040251Y+006711               S3      
317GND              VIA   -     D0100PA00X+040251Y+011711               S3      
317GND              VIA   -     D0100PA00X+040251Y+016711               S3      
317GND              VIA   -     D0100PA00X+040251Y+021711               S3      
317GND              VIA   -     D0100PA00X+040251Y+026711               S3      
317GND              VIA   -     D0100PA00X+040251Y+031711               S3      
317GND              VIA   -     D0100PA00X+040251Y+036711               S3      
317GND              VIA   -     D0100PA00X+040251Y+041711               S3      
317GND              VIA   -     D0100PA00X+040251Y+046711               S3      
317GND              VIA   -     D0100PA00X+040251Y+051711               S3      
317GND              VIA   -     D0100PA00X+040251Y+056711               S3      
317GND              VIA   -     D0100PA00X+040251Y+061711               S3      
317GND              VIA   -     D0100PA00X+040251Y+066711               S3      
317GND              VIA   -     D0100PA00X+040251Y+071711               S3      
317GND              VIA   -     D0100PA00X+040251Y+076711               S3      
317GND              VIA   -     D0100PA00X+040251Y+081711               S3      
317GND              VIA   -     D0100PA00X+040251Y+086711               S3      
317GND              VIA   -     D0100PA00X+040251Y+091711               S3      
317GND              VIA   -     D0100PA00X+040251Y+096711               S3      
317GND              VIA   -     D0100PA00X+040251Y+101711               S3      
317GND              VIA   -     D0100PA00X+040251Y+106711               S3      
317GND              VIA   -     D0100PA00X+040251Y+111711               S3      
317GND              VIA   -     D0100PA00X+040251Y+116711               S3      
317GND              VIA   -     D0100PA00X+040251Y+121711               S3      
317GND              VIA   -     D0100PA00X+040251Y+126711               S3      
317GND              VIA   -     D0100PA00X+040251Y+131711               S3      
317GND              VIA   -     D0100PA00X+040251Y+136711               S3      
317GND              VIA   -     D0100PA00X+040251Y+141711               S3      
317GND              VIA   -     D0100PA00X+040251Y+146711               S3      
317GND              VIA   -     D0100PA00X+040251Y+151711               S3      
317GND              VIA   -     D0100PA00X+040251Y+156711               S3      
317GND              VIA   -     D0100PA00X+040251Y+161711               S3      
317GND              VIA   -     D0100PA00X+040251Y+166711               S3      
317GND              VIA   -     D0100PA00X+040251Y+171711               S3      
317GND              VIA   -     D0100PA00X+040251Y+176711               S3      
317GND              VIA   -     D0100PA00X+040251Y+181711               S3      
317GND              VIA   -     D0100PA00X+040251Y+186711               S3      
317GND              VIA   -     D0100PA00X+040251Y+191711               S3      
317GND              VIA   -     D0100PA00X+040251Y+196711               S3      
317GND              VIA   -     D0100PA00X+040251Y+201711               S3      
317GND              VIA   -     D0100PA00X+040251Y+206711               S3      
P  NNAME10000 UART_CTS_P1_L_N
P  NNAME10001 UART_CTS_P2_L_N
P  NNAME10002 UART_DTR_P1_L_N
P  NNAME10003 UART_DSR_P1_L_N
P  NNAME10004 UART_CTS_P5_L_N
P  NNAME10005 UART_DSR_P2_L_N
P  NNAME10006 UART_CTS_P6_L_N
P  NNAME10007 UART_RTS_P1_L_N
P  NNAME10008 UART_DTR_P5_L_N
P  NNAME10009 UART_DSR_P5_L_N
P  NNAME10010 UART_DSR_P6_L_N
P  NNAME10011 UART_RTS_P5_L_N
P  NNAME10012 TP_T10_BLAD4_EN
P  NNAME10013 TP_T10_BLAD2_EN
P  NNAME10014 TP_T12_BLAD4_EN
P  NNAME10015 TP_T12_BLAD2_EN
P  NNAME10016 POWER_SW1_PWR_CTR_12V
P  NNAME10017 POWER_SW3_PWR_CTR_12V
P  NNAME10018 POWER_SW2_PWR_CTR_12V
P  NNAME10019 UART_DTR_P2_L_N
P  NNAME10020 UART_RTS_P2_L_N
P  NNAME10021 UART_DTR_P6_L_N
P  NNAME10022 UART_RTS_P6_L_N
P  NNAME10023 TP_T11_BLAD4_EN
P  NNAME10024 TP_T11_BLAD2_EN
P  NNAME10025 PSU6_REMOTE_R_P
P  NNAME10026 PSU6_REMOTE_R_N
P  NNAME10027 PSU4_REMOTE_R_P
P  NNAME10028 PSU4_REMOTE_R_N
P  NNAME10029 PSU1_REMOTE_R2_N
P  NNAME10030 PSU1_REMOTE_R_N
P  NNAME10031 PSU2_REMOTE_R_N
P  NNAME10032 PSU2_REMOTE_R2_N
P  NNAME10033 PSU3_REMOTE_R_N
P  NNAME10034 PSU3_REMOTE_R2_N
P  NNAME10035 PSU3_REMOTE_R_P
P  NNAME10036 PSU4_REMOTE_R2_N
P  NNAME10037 PSU5_REMOTE_R_N
P  NNAME10038 PSU5_REMOTE_R2_N
P  NNAME10039 PSU6_REMOTE_R2_N
P  NNAME10040 PSU1_REMOTE_R_P
P  NNAME10041 PSU1_REMOTE_R2_P
P  NNAME10042 PSU2_REMOTE_R_P
P  NNAME10043 PSU2_REMOTE_R2_P
P  NNAME10044 PSU3_REMOTE_R2_P
P  NNAME10045 PSU4_REMOTE_R2_P
P  NNAME10046 PSU5_REMOTE_R2_P
P  NNAME10047 PSU5_REMOTE_R_P
P  NNAME10048 PSU6_REMOTE_R2_P
P  NNAME10049 B11_PSU_ALERT_N
P  NNAME10050 B10_PSU_ALERT_N
P  NNAME10051 B12_PSU_ALERT_N
P  NNAME10052 B14_PSU_ALERT_N
P  NNAME10053 B13_PSU_ALERT_N
P  NNAME10054 B16_PSU_ALERT_N
P  NNAME10055 B15_PSU_ALERT_N
P  NNAME10056 B18_PSU_ALERT_N
P  NNAME10057 B17_PSU_ALERT_N
P  NNAME10058 B20_PSU_ALERT_N
P  NNAME10059 B19_PSU_ALERT_N
P  NNAME10060 B22_PSU_ALERT_N
P  NNAME10061 B21_PSU_ALERT_N
P  NNAME10062 B24_PSU_ALERT_N
P  NNAME10063 B23_PSU_ALERT_N
999
